(kicad_sch
	(version 20250114)
	(generator "eeschema")
	(generator_version "9.0")
	(paper "A3")
	(title_block
		(title "CM4 Baseboard")
		(date "2026-01-05")
		(rev "1.1.1")
		(company "Antmicro Ltd")
		(comment 1 "www.antmicro.com")
	)
	(text "SDIO.CD = H -> card inserted "
		(exclude_from_sim no)
		(at 198.12 222.25 0)
		(effects
			(font
				(size 1.27 1.27)
			)
			(justify left bottom)
		)
	)
	(text "Note:\nCM4 supports only PCIe 2.0x1"
		(exclude_from_sim no)
		(at 149.86 20.32 0)
		(effects
			(font
				(size 1.27 1.27)
			)
			(justify left bottom)
		)
	)
	(text "Note:\nRPi4 CM4 includes TX AC coupling capacitors\nsee: https://datasheets.raspberrypi.com/cm4/cm4-datasheet.pdf page 7\n"
		(exclude_from_sim no)
		(at 149.86 27.94 0)
		(effects
			(font
				(size 1.27 1.27)
			)
			(justify left bottom)
		)
	)
	(text "Note:\nPlace close to\npins 12,14,16,18"
		(exclude_from_sim no)
		(at 229.87 45.72 0)
		(effects
			(font
				(size 1.27 1.27)
			)
			(justify left bottom)
		)
	)
	(text "Note:\nPlace close to\npins 2,4"
		(exclude_from_sim no)
		(at 248.92 45.72 0)
		(effects
			(font
				(size 1.27 1.27)
			)
			(justify left bottom)
		)
	)
	(text "Micro SD card slot"
		(exclude_from_sim no)
		(at 175.768 169.164 0)
		(effects
			(font
				(size 2.54 2.54)
				(bold yes)
			)
			(justify left bottom)
		)
	)
	(text "Note:\nPlace close to\npins 70,72,74"
		(exclude_from_sim no)
		(at 213.36 45.72 0)
		(effects
			(font
				(size 1.27 1.27)
			)
			(justify left bottom)
		)
	)
	(text "M.2 NVME"
		(exclude_from_sim no)
		(at 111.76 21.59 0)
		(effects
			(font
				(size 2.54 2.54)
				(bold yes)
			)
			(justify left bottom)
		)
	)
	(junction
		(at 151.13 229.87)
		(diameter 0)
		(color 0 0 0 0)
	)
	(junction
		(at 224.79 46.99)
		(diameter 0)
		(color 0 0 0 0)
	)
	(junction
		(at 226.06 199.39)
		(diameter 0)
		(color 0 0 0 0)
	)
	(junction
		(at 242.57 46.99)
		(diameter 0)
		(color 0 0 0 0)
	)
	(junction
		(at 187.96 217.17)
		(diameter 0)
		(color 0 0 0 0)
	)
	(junction
		(at 204.47 124.46)
		(diameter 0)
		(color 0 0 0 0)
	)
	(junction
		(at 203.2 209.55)
		(diameter 0)
		(color 0 0 0 0)
	)
	(junction
		(at 210.82 204.47)
		(diameter 0)
		(color 0 0 0 0)
	)
	(junction
		(at 218.44 189.23)
		(diameter 0)
		(color 0 0 0 0)
	)
	(junction
		(at 162.56 49.53)
		(diameter 0)
		(color 0 0 0 0)
	)
	(junction
		(at 217.17 46.99)
		(diameter 0)
		(color 0 0 0 0)
	)
	(junction
		(at 210.82 189.23)
		(diameter 0)
		(color 0 0 0 0)
	)
	(junction
		(at 234.95 222.25)
		(diameter 0)
		(color 0 0 0 0)
	)
	(junction
		(at 256.54 59.69)
		(diameter 0)
		(color 0 0 0 0)
	)
	(junction
		(at 205.74 189.23)
		(diameter 0)
		(color 0 0 0 0)
	)
	(junction
		(at 220.98 59.69)
		(diameter 0)
		(color 0 0 0 0)
	)
	(junction
		(at 203.2 189.23)
		(diameter 0)
		(color 0 0 0 0)
	)
	(junction
		(at 234.95 46.99)
		(diameter 0)
		(color 0 0 0 0)
	)
	(junction
		(at 238.76 59.69)
		(diameter 0)
		(color 0 0 0 0)
	)
	(junction
		(at 260.35 46.99)
		(diameter 0)
		(color 0 0 0 0)
	)
	(junction
		(at 154.94 35.56)
		(diameter 0)
		(color 0 0 0 0)
	)
	(junction
		(at 195.58 214.63)
		(diameter 0)
		(color 0 0 0 0)
	)
	(junction
		(at 154.94 46.99)
		(diameter 0)
		(color 0 0 0 0)
	)
	(junction
		(at 195.58 189.23)
		(diameter 0)
		(color 0 0 0 0)
	)
	(junction
		(at 252.73 46.99)
		(diameter 0)
		(color 0 0 0 0)
	)
	(junction
		(at 162.56 35.56)
		(diameter 0)
		(color 0 0 0 0)
	)
	(junction
		(at 218.44 201.93)
		(diameter 0)
		(color 0 0 0 0)
	)
	(junction
		(at 226.06 189.23)
		(diameter 0)
		(color 0 0 0 0)
	)
	(bus_entry
		(at 133.35 121.92)
		(size 2.54 2.54)
		(stroke
			(width 0)
			(type default)
		)
	)
	(bus_entry
		(at 173.99 212.09)
		(size -2.54 2.54)
		(stroke
			(width 0)
			(type default)
		)
	)
	(bus_entry
		(at 173.99 194.31)
		(size -2.54 2.54)
		(stroke
			(width 0)
			(type default)
		)
	)
	(bus_entry
		(at 173.99 201.93)
		(size 2.54 2.54)
		(stroke
			(width 0)
			(type default)
		)
	)
	(bus_entry
		(at 133.35 68.58)
		(size 2.54 2.54)
		(stroke
			(width 0)
			(type default)
		)
	)
	(bus_entry
		(at 173.99 212.09)
		(size 2.54 2.54)
		(stroke
			(width 0)
			(type default)
		)
	)
	(bus_entry
		(at 133.35 66.04)
		(size 2.54 2.54)
		(stroke
			(width 0)
			(type default)
		)
	)
	(bus_entry
		(at 133.35 111.76)
		(size 2.54 2.54)
		(stroke
			(width 0)
			(type default)
		)
	)
	(bus_entry
		(at 133.35 96.52)
		(size 2.54 2.54)
		(stroke
			(width 0)
			(type default)
		)
	)
	(bus_entry
		(at 133.35 119.38)
		(size 2.54 2.54)
		(stroke
			(width 0)
			(type default)
		)
	)
	(bus_entry
		(at 133.35 81.28)
		(size 2.54 2.54)
		(stroke
			(width 0)
			(type default)
		)
	)
	(bus_entry
		(at 173.99 199.39)
		(size -2.54 2.54)
		(stroke
			(width 0)
			(type default)
		)
	)
	(bus_entry
		(at 173.99 196.85)
		(size 2.54 2.54)
		(stroke
			(width 0)
			(type default)
		)
	)
	(bus_entry
		(at 133.35 83.82)
		(size 2.54 2.54)
		(stroke
			(width 0)
			(type default)
		)
	)
	(bus_entry
		(at 173.99 201.93)
		(size -2.54 2.54)
		(stroke
			(width 0)
			(type default)
		)
	)
	(bus_entry
		(at 133.35 106.68)
		(size 2.54 2.54)
		(stroke
			(width 0)
			(type default)
		)
	)
	(bus_entry
		(at 173.99 196.85)
		(size -2.54 2.54)
		(stroke
			(width 0)
			(type default)
		)
	)
	(bus_entry
		(at 133.35 99.06)
		(size 2.54 2.54)
		(stroke
			(width 0)
			(type default)
		)
	)
	(bus_entry
		(at 133.35 59.69)
		(size 2.54 2.54)
		(stroke
			(width 0)
			(type default)
		)
	)
	(bus_entry
		(at 173.99 214.63)
		(size 2.54 2.54)
		(stroke
			(width 0)
			(type default)
		)
	)
	(bus_entry
		(at 173.99 199.39)
		(size 2.54 2.54)
		(stroke
			(width 0)
			(type default)
		)
	)
	(bus_entry
		(at 133.35 88.9)
		(size 2.54 2.54)
		(stroke
			(width 0)
			(type default)
		)
	)
	(bus_entry
		(at 133.35 76.2)
		(size 2.54 2.54)
		(stroke
			(width 0)
			(type default)
		)
	)
	(bus_entry
		(at 173.99 214.63)
		(size -2.54 2.54)
		(stroke
			(width 0)
			(type default)
		)
	)
	(bus_entry
		(at 173.99 207.01)
		(size -2.54 2.54)
		(stroke
			(width 0)
			(type default)
		)
	)
	(bus_entry
		(at 133.35 114.3)
		(size 2.54 2.54)
		(stroke
			(width 0)
			(type default)
		)
	)
	(bus_entry
		(at 133.35 44.45)
		(size 2.54 2.54)
		(stroke
			(width 0)
			(type default)
		)
	)
	(bus_entry
		(at 133.35 104.14)
		(size 2.54 2.54)
		(stroke
			(width 0)
			(type default)
		)
	)
	(bus_entry
		(at 133.35 73.66)
		(size 2.54 2.54)
		(stroke
			(width 0)
			(type default)
		)
	)
	(bus_entry
		(at 133.35 57.15)
		(size 2.54 2.54)
		(stroke
			(width 0)
			(type default)
		)
	)
	(bus_entry
		(at 133.35 91.44)
		(size 2.54 2.54)
		(stroke
			(width 0)
			(type default)
		)
	)
	(bus_entry
		(at 173.99 207.01)
		(size 2.54 2.54)
		(stroke
			(width 0)
			(type default)
		)
	)
	(bus_entry
		(at 173.99 219.71)
		(size 2.54 2.54)
		(stroke
			(width 0)
			(type default)
		)
	)
	(bus_entry
		(at 133.35 46.99)
		(size 2.54 2.54)
		(stroke
			(width 0)
			(type default)
		)
	)
	(bus
		(pts
			(xy 133.35 104.14) (xy 133.35 106.68)
		)
		(stroke
			(width 0)
			(type default)
		)
	)
	(wire
		(pts
			(xy 170.18 41.91) (xy 170.18 52.07)
		)
		(stroke
			(width 0)
			(type default)
		)
	)
	(bus
		(pts
			(xy 133.35 111.76) (xy 133.35 114.3)
		)
		(stroke
			(width 0)
			(type default)
		)
	)
	(wire
		(pts
			(xy 204.47 121.92) (xy 204.47 124.46)
		)
		(stroke
			(width 0)
			(type default)
		)
	)
	(wire
		(pts
			(xy 172.72 76.2) (xy 135.89 76.2)
		)
		(stroke
			(width 0)
			(type default)
		)
	)
	(wire
		(pts
			(xy 172.72 83.82) (xy 135.89 83.82)
		)
		(stroke
			(width 0)
			(type default)
		)
	)
	(wire
		(pts
			(xy 176.53 209.55) (xy 203.2 209.55)
		)
		(stroke
			(width 0)
			(type default)
		)
	)
	(wire
		(pts
			(xy 187.96 217.17) (xy 243.84 217.17)
		)
		(stroke
			(width 0)
			(type default)
		)
	)
	(wire
		(pts
			(xy 154.94 35.56) (xy 154.94 36.83)
		)
		(stroke
			(width 0)
			(type default)
		)
	)
	(wire
		(pts
			(xy 242.57 46.99) (xy 242.57 49.53)
		)
		(stroke
			(width 0)
			(type default)
		)
	)
	(bus
		(pts
			(xy 173.99 214.63) (xy 173.99 219.71)
		)
		(stroke
			(width 0)
			(type default)
		)
	)
	(wire
		(pts
			(xy 252.73 46.99) (xy 252.73 49.53)
		)
		(stroke
			(width 0)
			(type default)
		)
	)
	(wire
		(pts
			(xy 154.94 46.99) (xy 172.72 46.99)
		)
		(stroke
			(width 0)
			(type default)
		)
	)
	(wire
		(pts
			(xy 217.17 54.61) (xy 217.17 59.69)
		)
		(stroke
			(width 0)
			(type default)
		)
	)
	(wire
		(pts
			(xy 162.56 49.53) (xy 172.72 49.53)
		)
		(stroke
			(width 0)
			(type default)
		)
	)
	(polyline
		(pts
			(xy 224.79 30.48) (xy 224.79 15.24)
		)
		(stroke
			(width 0)
			(type default)
		)
	)
	(wire
		(pts
			(xy 172.72 116.84) (xy 135.89 116.84)
		)
		(stroke
			(width 0)
			(type default)
		)
	)
	(wire
		(pts
			(xy 217.17 59.69) (xy 220.98 59.69)
		)
		(stroke
			(width 0)
			(type default)
		)
	)
	(wire
		(pts
			(xy 217.17 46.99) (xy 217.17 49.53)
		)
		(stroke
			(width 0)
			(type default)
		)
	)
	(wire
		(pts
			(xy 149.86 219.71) (xy 151.13 219.71)
		)
		(stroke
			(width 0)
			(type default)
		)
	)
	(wire
		(pts
			(xy 172.72 121.92) (xy 135.89 121.92)
		)
		(stroke
			(width 0)
			(type default)
		)
	)
	(wire
		(pts
			(xy 234.95 46.99) (xy 234.95 49.53)
		)
		(stroke
			(width 0)
			(type default)
		)
	)
	(polyline
		(pts
			(xy 212.09 39.37) (xy 212.09 60.96)
		)
		(stroke
			(width 0)
			(type default)
		)
	)
	(polyline
		(pts
			(xy 246.38 60.96) (xy 229.87 60.96)
		)
		(stroke
			(width 0)
			(type default)
		)
	)
	(wire
		(pts
			(xy 234.95 59.69) (xy 238.76 59.69)
		)
		(stroke
			(width 0)
			(type default)
		)
	)
	(wire
		(pts
			(xy 218.44 189.23) (xy 218.44 191.77)
		)
		(stroke
			(width 0)
			(type default)
		)
	)
	(wire
		(pts
			(xy 176.53 214.63) (xy 195.58 214.63)
		)
		(stroke
			(width 0)
			(type default)
		)
	)
	(wire
		(pts
			(xy 172.72 124.46) (xy 135.89 124.46)
		)
		(stroke
			(width 0)
			(type default)
		)
	)
	(wire
		(pts
			(xy 172.72 59.69) (xy 135.89 59.69)
		)
		(stroke
			(width 0)
			(type default)
		)
	)
	(wire
		(pts
			(xy 149.86 207.01) (xy 151.13 207.01)
		)
		(stroke
			(width 0)
			(type default)
		)
	)
	(wire
		(pts
			(xy 187.96 196.85) (xy 187.96 217.17)
		)
		(stroke
			(width 0)
			(type default)
		)
	)
	(polyline
		(pts
			(xy 212.09 39.37) (xy 228.6 39.37)
		)
		(stroke
			(width 0)
			(type default)
		)
	)
	(polyline
		(pts
			(xy 12.7 142.24) (xy 407.67 142.24)
		)
		(stroke
			(width 0)
			(type default)
		)
	)
	(wire
		(pts
			(xy 224.79 54.61) (xy 224.79 59.69)
		)
		(stroke
			(width 0)
			(type default)
		)
	)
	(wire
		(pts
			(xy 149.86 224.79) (xy 158.75 224.79)
		)
		(stroke
			(width 0)
			(type default)
		)
	)
	(polyline
		(pts
			(xy 264.16 60.96) (xy 247.65 60.96)
		)
		(stroke
			(width 0)
			(type default)
		)
	)
	(bus
		(pts
			(xy 133.35 59.69) (xy 133.35 66.04)
		)
		(stroke
			(width 0)
			(type default)
		)
	)
	(wire
		(pts
			(xy 154.94 35.56) (xy 153.67 35.56)
		)
		(stroke
			(width 0)
			(type default)
		)
	)
	(wire
		(pts
			(xy 135.89 49.53) (xy 162.56 49.53)
		)
		(stroke
			(width 0)
			(type default)
		)
	)
	(wire
		(pts
			(xy 151.13 207.01) (xy 151.13 208.28)
		)
		(stroke
			(width 0)
			(type default)
		)
	)
	(wire
		(pts
			(xy 234.95 219.71) (xy 243.84 219.71)
		)
		(stroke
			(width 0)
			(type default)
		)
	)
	(wire
		(pts
			(xy 149.86 229.87) (xy 151.13 229.87)
		)
		(stroke
			(width 0)
			(type default)
		)
	)
	(wire
		(pts
			(xy 203.2 189.23) (xy 203.2 191.77)
		)
		(stroke
			(width 0)
			(type default)
		)
	)
	(wire
		(pts
			(xy 203.2 189.23) (xy 205.74 189.23)
		)
		(stroke
			(width 0)
			(type default)
		)
	)
	(wire
		(pts
			(xy 203.2 46.99) (xy 217.17 46.99)
		)
		(stroke
			(width 0)
			(type default)
		)
	)
	(wire
		(pts
			(xy 252.73 46.99) (xy 260.35 46.99)
		)
		(stroke
			(width 0)
			(type default)
		)
	)
	(polyline
		(pts
			(xy 264.16 39.37) (xy 264.16 60.96)
		)
		(stroke
			(width 0)
			(type default)
		)
	)
	(wire
		(pts
			(xy 210.82 204.47) (xy 243.84 204.47)
		)
		(stroke
			(width 0)
			(type default)
		)
	)
	(bus
		(pts
			(xy 133.35 114.3) (xy 133.35 119.38)
		)
		(stroke
			(width 0)
			(type default)
		)
	)
	(wire
		(pts
			(xy 176.53 217.17) (xy 187.96 217.17)
		)
		(stroke
			(width 0)
			(type default)
		)
	)
	(wire
		(pts
			(xy 256.54 59.69) (xy 260.35 59.69)
		)
		(stroke
			(width 0)
			(type default)
		)
	)
	(bus
		(pts
			(xy 133.35 46.99) (xy 133.35 57.15)
		)
		(stroke
			(width 0)
			(type default)
		)
	)
	(wire
		(pts
			(xy 226.06 196.85) (xy 226.06 199.39)
		)
		(stroke
			(width 0)
			(type default)
		)
	)
	(wire
		(pts
			(xy 170.18 35.56) (xy 162.56 35.56)
		)
		(stroke
			(width 0)
			(type default)
		)
	)
	(wire
		(pts
			(xy 157.48 222.25) (xy 157.48 209.55)
		)
		(stroke
			(width 0)
			(type default)
		)
	)
	(wire
		(pts
			(xy 172.72 114.3) (xy 135.89 114.3)
		)
		(stroke
			(width 0)
			(type default)
		)
	)
	(wire
		(pts
			(xy 210.82 189.23) (xy 218.44 189.23)
		)
		(stroke
			(width 0)
			(type default)
		)
	)
	(bus
		(pts
			(xy 133.35 76.2) (xy 133.35 81.28)
		)
		(stroke
			(width 0)
			(type default)
		)
	)
	(wire
		(pts
			(xy 285.75 191.77) (xy 285.75 193.04)
		)
		(stroke
			(width 0)
			(type default)
		)
	)
	(wire
		(pts
			(xy 176.53 199.39) (xy 226.06 199.39)
		)
		(stroke
			(width 0)
			(type default)
		)
	)
	(wire
		(pts
			(xy 172.72 101.6) (xy 135.89 101.6)
		)
		(stroke
			(width 0)
			(type default)
		)
	)
	(bus
		(pts
			(xy 133.35 68.58) (xy 133.35 73.66)
		)
		(stroke
			(width 0)
			(type default)
		)
	)
	(wire
		(pts
			(xy 266.7 119.38) (xy 266.7 121.92)
		)
		(stroke
			(width 0)
			(type default)
		)
	)
	(wire
		(pts
			(xy 226.06 199.39) (xy 243.84 199.39)
		)
		(stroke
			(width 0)
			(type default)
		)
	)
	(wire
		(pts
			(xy 203.2 209.55) (xy 243.84 209.55)
		)
		(stroke
			(width 0)
			(type default)
		)
	)
	(bus
		(pts
			(xy 133.35 106.68) (xy 133.35 111.76)
		)
		(stroke
			(width 0)
			(type default)
		)
	)
	(wire
		(pts
			(xy 220.98 59.69) (xy 220.98 62.23)
		)
		(stroke
			(width 0)
			(type default)
		)
	)
	(wire
		(pts
			(xy 204.47 125.73) (xy 204.47 124.46)
		)
		(stroke
			(width 0)
			(type default)
		)
	)
	(wire
		(pts
			(xy 226.06 189.23) (xy 226.06 191.77)
		)
		(stroke
			(width 0)
			(type default)
		)
	)
	(bus
		(pts
			(xy 133.35 81.28) (xy 133.35 83.82)
		)
		(stroke
			(width 0)
			(type default)
		)
	)
	(wire
		(pts
			(xy 195.58 189.23) (xy 195.58 191.77)
		)
		(stroke
			(width 0)
			(type default)
		)
	)
	(wire
		(pts
			(xy 243.84 207.01) (xy 242.57 207.01)
		)
		(stroke
			(width 0)
			(type default)
		)
	)
	(wire
		(pts
			(xy 149.86 222.25) (xy 157.48 222.25)
		)
		(stroke
			(width 0)
			(type default)
		)
	)
	(polyline
		(pts
			(xy 229.87 39.37) (xy 229.87 60.96)
		)
		(stroke
			(width 0)
			(type default)
		)
	)
	(wire
		(pts
			(xy 172.72 68.58) (xy 135.89 68.58)
		)
		(stroke
			(width 0)
			(type default)
		)
	)
	(polyline
		(pts
			(xy 228.6 39.37) (xy 228.6 60.96)
		)
		(stroke
			(width 0)
			(type default)
		)
	)
	(wire
		(pts
			(xy 149.86 201.93) (xy 171.45 201.93)
		)
		(stroke
			(width 0)
			(type default)
		)
	)
	(wire
		(pts
			(xy 260.35 46.99) (xy 267.97 46.99)
		)
		(stroke
			(width 0)
			(type default)
		)
	)
	(bus
		(pts
			(xy 173.99 201.93) (xy 173.99 207.01)
		)
		(stroke
			(width 0)
			(type default)
		)
	)
	(wire
		(pts
			(xy 242.57 207.01) (xy 242.57 185.42)
		)
		(stroke
			(width 0)
			(type default)
		)
	)
	(wire
		(pts
			(xy 170.18 52.07) (xy 172.72 52.07)
		)
		(stroke
			(width 0)
			(type default)
		)
	)
	(polyline
		(pts
			(xy 247.65 39.37) (xy 247.65 60.96)
		)
		(stroke
			(width 0)
			(type default)
		)
	)
	(wire
		(pts
			(xy 220.98 59.69) (xy 224.79 59.69)
		)
		(stroke
			(width 0)
			(type default)
		)
	)
	(bus
		(pts
			(xy 133.35 39.37) (xy 133.35 44.45)
		)
		(stroke
			(width 0)
			(type default)
		)
	)
	(wire
		(pts
			(xy 172.72 93.98) (xy 135.89 93.98)
		)
		(stroke
			(width 0)
			(type default)
		)
	)
	(polyline
		(pts
			(xy 148.59 30.48) (xy 224.79 30.48)
		)
		(stroke
			(width 0)
			(type default)
		)
	)
	(wire
		(pts
			(xy 172.72 99.06) (xy 135.89 99.06)
		)
		(stroke
			(width 0)
			(type default)
		)
	)
	(wire
		(pts
			(xy 203.2 196.85) (xy 203.2 209.55)
		)
		(stroke
			(width 0)
			(type default)
		)
	)
	(wire
		(pts
			(xy 187.96 189.23) (xy 195.58 189.23)
		)
		(stroke
			(width 0)
			(type default)
		)
	)
	(wire
		(pts
			(xy 205.74 101.6) (xy 203.2 101.6)
		)
		(stroke
			(width 0)
			(type default)
		)
	)
	(bus
		(pts
			(xy 133.35 57.15) (xy 133.35 59.69)
		)
		(stroke
			(width 0)
			(type default)
		)
	)
	(polyline
		(pts
			(xy 148.59 15.24) (xy 224.79 15.24)
		)
		(stroke
			(width 0)
			(type default)
		)
	)
	(wire
		(pts
			(xy 218.44 196.85) (xy 218.44 201.93)
		)
		(stroke
			(width 0)
			(type default)
		)
	)
	(wire
		(pts
			(xy 205.74 185.42) (xy 205.74 189.23)
		)
		(stroke
			(width 0)
			(type default)
		)
	)
	(wire
		(pts
			(xy 149.86 204.47) (xy 171.45 204.47)
		)
		(stroke
			(width 0)
			(type default)
		)
	)
	(wire
		(pts
			(xy 217.17 46.99) (xy 224.79 46.99)
		)
		(stroke
			(width 0)
			(type default)
		)
	)
	(wire
		(pts
			(xy 160.02 227.33) (xy 160.02 217.17)
		)
		(stroke
			(width 0)
			(type default)
		)
	)
	(wire
		(pts
			(xy 267.97 219.71) (xy 267.97 224.79)
		)
		(stroke
			(width 0)
			(type default)
		)
	)
	(wire
		(pts
			(xy 170.18 35.56) (xy 170.18 36.83)
		)
		(stroke
			(width 0)
			(type default)
		)
	)
	(wire
		(pts
			(xy 172.72 109.22) (xy 135.89 109.22)
		)
		(stroke
			(width 0)
			(type default)
		)
	)
	(bus
		(pts
			(xy 133.35 119.38) (xy 133.35 121.92)
		)
		(stroke
			(width 0)
			(type default)
		)
	)
	(bus
		(pts
			(xy 173.99 184.15) (xy 173.99 194.31)
		)
		(stroke
			(width 0)
			(type default)
		)
	)
	(bus
		(pts
			(xy 133.35 44.45) (xy 133.35 46.99)
		)
		(stroke
			(width 0)
			(type default)
		)
	)
	(wire
		(pts
			(xy 252.73 54.61) (xy 252.73 59.69)
		)
		(stroke
			(width 0)
			(type default)
		)
	)
	(wire
		(pts
			(xy 176.53 222.25) (xy 186.69 222.25)
		)
		(stroke
			(width 0)
			(type default)
		)
	)
	(wire
		(pts
			(xy 205.74 100.33) (xy 205.74 101.6)
		)
		(stroke
			(width 0)
			(type default)
		)
	)
	(wire
		(pts
			(xy 151.13 219.71) (xy 151.13 229.87)
		)
		(stroke
			(width 0)
			(type default)
		)
	)
	(wire
		(pts
			(xy 195.58 214.63) (xy 243.84 214.63)
		)
		(stroke
			(width 0)
			(type default)
		)
	)
	(wire
		(pts
			(xy 172.72 71.12) (xy 135.89 71.12)
		)
		(stroke
			(width 0)
			(type default)
		)
	)
	(wire
		(pts
			(xy 242.57 212.09) (xy 242.57 224.79)
		)
		(stroke
			(width 0)
			(type default)
		)
	)
	(wire
		(pts
			(xy 238.76 59.69) (xy 242.57 59.69)
		)
		(stroke
			(width 0)
			(type default)
		)
	)
	(wire
		(pts
			(xy 234.95 54.61) (xy 234.95 59.69)
		)
		(stroke
			(width 0)
			(type default)
		)
	)
	(wire
		(pts
			(xy 187.96 189.23) (xy 187.96 191.77)
		)
		(stroke
			(width 0)
			(type default)
		)
	)
	(wire
		(pts
			(xy 260.35 54.61) (xy 260.35 59.69)
		)
		(stroke
			(width 0)
			(type default)
		)
	)
	(wire
		(pts
			(xy 162.56 41.91) (xy 162.56 49.53)
		)
		(stroke
			(width 0)
			(type default)
		)
	)
	(polyline
		(pts
			(xy 229.87 39.37) (xy 246.38 39.37)
		)
		(stroke
			(width 0)
			(type default)
		)
	)
	(wire
		(pts
			(xy 275.59 191.77) (xy 275.59 193.04)
		)
		(stroke
			(width 0)
			(type default)
		)
	)
	(wire
		(pts
			(xy 158.75 224.79) (xy 158.75 214.63)
		)
		(stroke
			(width 0)
			(type default)
		)
	)
	(wire
		(pts
			(xy 260.35 46.99) (xy 260.35 49.53)
		)
		(stroke
			(width 0)
			(type default)
		)
	)
	(wire
		(pts
			(xy 205.74 189.23) (xy 210.82 189.23)
		)
		(stroke
			(width 0)
			(type default)
		)
	)
	(wire
		(pts
			(xy 234.95 46.99) (xy 242.57 46.99)
		)
		(stroke
			(width 0)
			(type default)
		)
	)
	(wire
		(pts
			(xy 218.44 189.23) (xy 226.06 189.23)
		)
		(stroke
			(width 0)
			(type default)
		)
	)
	(wire
		(pts
			(xy 234.95 191.77) (xy 234.95 189.23)
		)
		(stroke
			(width 0)
			(type default)
		)
	)
	(bus
		(pts
			(xy 133.35 73.66) (xy 133.35 76.2)
		)
		(stroke
			(width 0)
			(type default)
		)
	)
	(wire
		(pts
			(xy 204.47 124.46) (xy 203.2 124.46)
		)
		(stroke
			(width 0)
			(type default)
		)
	)
	(wire
		(pts
			(xy 172.72 62.23) (xy 135.89 62.23)
		)
		(stroke
			(width 0)
			(type default)
		)
	)
	(wire
		(pts
			(xy 203.2 121.92) (xy 204.47 121.92)
		)
		(stroke
			(width 0)
			(type default)
		)
	)
	(wire
		(pts
			(xy 154.94 41.91) (xy 154.94 46.99)
		)
		(stroke
			(width 0)
			(type default)
		)
	)
	(wire
		(pts
			(xy 275.59 198.12) (xy 275.59 199.39)
		)
		(stroke
			(width 0)
			(type default)
		)
	)
	(polyline
		(pts
			(xy 246.38 39.37) (xy 246.38 60.96)
		)
		(stroke
			(width 0)
			(type default)
		)
	)
	(wire
		(pts
			(xy 238.76 59.69) (xy 238.76 62.23)
		)
		(stroke
			(width 0)
			(type default)
		)
	)
	(wire
		(pts
			(xy 157.48 209.55) (xy 171.45 209.55)
		)
		(stroke
			(width 0)
			(type default)
		)
	)
	(wire
		(pts
			(xy 204.47 76.2) (xy 203.2 76.2)
		)
		(stroke
			(width 0)
			(type default)
		)
	)
	(wire
		(pts
			(xy 256.54 59.69) (xy 256.54 62.23)
		)
		(stroke
			(width 0)
			(type default)
		)
	)
	(wire
		(pts
			(xy 234.95 222.25) (xy 234.95 224.79)
		)
		(stroke
			(width 0)
			(type default)
		)
	)
	(bus
		(pts
			(xy 124.46 39.37) (xy 133.35 39.37)
		)
		(stroke
			(width 0)
			(type default)
		)
	)
	(wire
		(pts
			(xy 172.72 86.36) (xy 135.89 86.36)
		)
		(stroke
			(width 0)
			(type default)
		)
	)
	(wire
		(pts
			(xy 204.47 73.66) (xy 203.2 73.66)
		)
		(stroke
			(width 0)
			(type default)
		)
	)
	(wire
		(pts
			(xy 162.56 35.56) (xy 162.56 36.83)
		)
		(stroke
			(width 0)
			(type default)
		)
	)
	(wire
		(pts
			(xy 205.74 93.98) (xy 205.74 95.25)
		)
		(stroke
			(width 0)
			(type default)
		)
	)
	(wire
		(pts
			(xy 243.84 212.09) (xy 242.57 212.09)
		)
		(stroke
			(width 0)
			(type default)
		)
	)
	(bus
		(pts
			(xy 133.35 99.06) (xy 133.35 104.14)
		)
		(stroke
			(width 0)
			(type default)
		)
	)
	(bus
		(pts
			(xy 133.35 91.44) (xy 133.35 96.52)
		)
		(stroke
			(width 0)
			(type default)
		)
	)
	(wire
		(pts
			(xy 176.53 201.93) (xy 218.44 201.93)
		)
		(stroke
			(width 0)
			(type default)
		)
	)
	(bus
		(pts
			(xy 173.99 196.85) (xy 173.99 199.39)
		)
		(stroke
			(width 0)
			(type default)
		)
	)
	(wire
		(pts
			(xy 172.72 78.74) (xy 135.89 78.74)
		)
		(stroke
			(width 0)
			(type default)
		)
	)
	(wire
		(pts
			(xy 149.86 227.33) (xy 160.02 227.33)
		)
		(stroke
			(width 0)
			(type default)
		)
	)
	(wire
		(pts
			(xy 224.79 46.99) (xy 234.95 46.99)
		)
		(stroke
			(width 0)
			(type default)
		)
	)
	(wire
		(pts
			(xy 160.02 217.17) (xy 171.45 217.17)
		)
		(stroke
			(width 0)
			(type default)
		)
	)
	(wire
		(pts
			(xy 172.72 106.68) (xy 135.89 106.68)
		)
		(stroke
			(width 0)
			(type default)
		)
	)
	(wire
		(pts
			(xy 242.57 54.61) (xy 242.57 59.69)
		)
		(stroke
			(width 0)
			(type default)
		)
	)
	(wire
		(pts
			(xy 151.13 229.87) (xy 151.13 231.14)
		)
		(stroke
			(width 0)
			(type default)
		)
	)
	(polyline
		(pts
			(xy 228.6 60.96) (xy 212.09 60.96)
		)
		(stroke
			(width 0)
			(type default)
		)
	)
	(wire
		(pts
			(xy 285.75 198.12) (xy 285.75 199.39)
		)
		(stroke
			(width 0)
			(type default)
		)
	)
	(bus
		(pts
			(xy 133.35 66.04) (xy 133.35 68.58)
		)
		(stroke
			(width 0)
			(type default)
		)
	)
	(wire
		(pts
			(xy 172.72 91.44) (xy 135.89 91.44)
		)
		(stroke
			(width 0)
			(type default)
		)
	)
	(wire
		(pts
			(xy 267.97 38.1) (xy 267.97 46.99)
		)
		(stroke
			(width 0)
			(type default)
		)
	)
	(wire
		(pts
			(xy 210.82 196.85) (xy 210.82 204.47)
		)
		(stroke
			(width 0)
			(type default)
		)
	)
	(wire
		(pts
			(xy 205.74 86.36) (xy 205.74 88.9)
		)
		(stroke
			(width 0)
			(type default)
		)
	)
	(wire
		(pts
			(xy 234.95 189.23) (xy 226.06 189.23)
		)
		(stroke
			(width 0)
			(type default)
		)
	)
	(wire
		(pts
			(xy 195.58 196.85) (xy 195.58 214.63)
		)
		(stroke
			(width 0)
			(type default)
		)
	)
	(wire
		(pts
			(xy 158.75 214.63) (xy 171.45 214.63)
		)
		(stroke
			(width 0)
			(type default)
		)
	)
	(wire
		(pts
			(xy 149.86 199.39) (xy 171.45 199.39)
		)
		(stroke
			(width 0)
			(type default)
		)
	)
	(wire
		(pts
			(xy 265.43 119.38) (xy 266.7 119.38)
		)
		(stroke
			(width 0)
			(type default)
		)
	)
	(wire
		(pts
			(xy 252.73 59.69) (xy 256.54 59.69)
		)
		(stroke
			(width 0)
			(type default)
		)
	)
	(wire
		(pts
			(xy 210.82 189.23) (xy 210.82 191.77)
		)
		(stroke
			(width 0)
			(type default)
		)
	)
	(wire
		(pts
			(xy 176.53 204.47) (xy 210.82 204.47)
		)
		(stroke
			(width 0)
			(type default)
		)
	)
	(bus
		(pts
			(xy 173.99 207.01) (xy 173.99 212.09)
		)
		(stroke
			(width 0)
			(type default)
		)
	)
	(wire
		(pts
			(xy 234.95 222.25) (xy 243.84 222.25)
		)
		(stroke
			(width 0)
			(type default)
		)
	)
	(wire
		(pts
			(xy 234.95 229.87) (xy 234.95 231.14)
		)
		(stroke
			(width 0)
			(type default)
		)
	)
	(wire
		(pts
			(xy 191.77 222.25) (xy 234.95 222.25)
		)
		(stroke
			(width 0)
			(type default)
		)
	)
	(wire
		(pts
			(xy 242.57 46.99) (xy 252.73 46.99)
		)
		(stroke
			(width 0)
			(type default)
		)
	)
	(wire
		(pts
			(xy 218.44 201.93) (xy 243.84 201.93)
		)
		(stroke
			(width 0)
			(type default)
		)
	)
	(bus
		(pts
			(xy 173.99 212.09) (xy 173.99 214.63)
		)
		(stroke
			(width 0)
			(type default)
		)
	)
	(bus
		(pts
			(xy 173.99 199.39) (xy 173.99 201.93)
		)
		(stroke
			(width 0)
			(type default)
		)
	)
	(wire
		(pts
			(xy 162.56 35.56) (xy 154.94 35.56)
		)
		(stroke
			(width 0)
			(type default)
		)
	)
	(bus
		(pts
			(xy 133.35 88.9) (xy 133.35 91.44)
		)
		(stroke
			(width 0)
			(type default)
		)
	)
	(wire
		(pts
			(xy 204.47 78.74) (xy 203.2 78.74)
		)
		(stroke
			(width 0)
			(type default)
		)
	)
	(bus
		(pts
			(xy 173.99 194.31) (xy 173.99 196.85)
		)
		(stroke
			(width 0)
			(type default)
		)
	)
	(bus
		(pts
			(xy 168.91 184.15) (xy 173.99 184.15)
		)
		(stroke
			(width 0)
			(type default)
		)
	)
	(wire
		(pts
			(xy 265.43 219.71) (xy 267.97 219.71)
		)
		(stroke
			(width 0)
			(type default)
		)
	)
	(wire
		(pts
			(xy 195.58 189.23) (xy 203.2 189.23)
		)
		(stroke
			(width 0)
			(type default)
		)
	)
	(wire
		(pts
			(xy 234.95 196.85) (xy 234.95 219.71)
		)
		(stroke
			(width 0)
			(type default)
		)
	)
	(bus
		(pts
			(xy 133.35 96.52) (xy 133.35 99.06)
		)
		(stroke
			(width 0)
			(type default)
		)
	)
	(polyline
		(pts
			(xy 247.65 39.37) (xy 264.16 39.37)
		)
		(stroke
			(width 0)
			(type default)
		)
	)
	(polyline
		(pts
			(xy 148.59 15.24) (xy 148.59 30.48)
		)
		(stroke
			(width 0)
			(type default)
		)
	)
	(bus
		(pts
			(xy 133.35 83.82) (xy 133.35 88.9)
		)
		(stroke
			(width 0)
			(type default)
		)
	)
	(wire
		(pts
			(xy 204.47 59.69) (xy 203.2 59.69)
		)
		(stroke
			(width 0)
			(type default)
		)
	)
	(wire
		(pts
			(xy 224.79 46.99) (xy 224.79 49.53)
		)
		(stroke
			(width 0)
			(type default)
		)
	)
	(wire
		(pts
			(xy 149.86 196.85) (xy 171.45 196.85)
		)
		(stroke
			(width 0)
			(type default)
		)
	)
	(wire
		(pts
			(xy 135.89 46.99) (xy 154.94 46.99)
		)
		(stroke
			(width 0)
			(type default)
		)
	)
	(label "NVMe.TX0_N"
		(at 148.59 71.12 180)
		(effects
			(font
				(size 1.27 1.27)
			)
			(justify right bottom)
		)
	)
	(label "NVMe.~{CLK_REQ}"
		(at 137.16 49.53 0)
		(effects
			(font
				(size 1.27 1.27)
			)
			(justify left bottom)
		)
	)
	(label "NVMe.RX2_N"
		(at 148.59 109.22 180)
		(effects
			(font
				(size 1.27 1.27)
			)
			(justify right bottom)
		)
	)
	(label "NVMe.RX0_P"
		(at 148.59 76.2 180)
		(effects
			(font
				(size 1.27 1.27)
			)
			(justify right bottom)
		)
	)
	(label "SDIO.CMD"
		(at 177.8 204.47 0)
		(effects
			(font
				(size 1.27 1.27)
			)
			(justify left bottom)
		)
	)
	(label "NVMe.TX2_P"
		(at 148.59 99.06 180)
		(effects
			(font
				(size 1.27 1.27)
			)
			(justify right bottom)
		)
	)
	(label "NVMe.RX2_P"
		(at 148.59 106.68 180)
		(effects
			(font
				(size 1.27 1.27)
			)
			(justify right bottom)
		)
	)
	(label "NVMe.RX1_N"
		(at 148.59 93.98 180)
		(effects
			(font
				(size 1.27 1.27)
			)
			(justify right bottom)
		)
	)
	(label "NVMe.TX2_N"
		(at 148.59 101.6 180)
		(effects
			(font
				(size 1.27 1.27)
			)
			(justify right bottom)
		)
	)
	(label "NVMe.~{RST}"
		(at 137.16 46.99 0)
		(effects
			(font
				(size 1.27 1.27)
			)
			(justify left bottom)
		)
	)
	(label "NVMe.RX1_P"
		(at 148.59 91.44 180)
		(effects
			(font
				(size 1.27 1.27)
			)
			(justify right bottom)
		)
	)
	(label "NVMe.TX1_P"
		(at 148.59 83.82 180)
		(effects
			(font
				(size 1.27 1.27)
			)
			(justify right bottom)
		)
	)
	(label "NVMe.CLK_N"
		(at 148.59 62.23 180)
		(effects
			(font
				(size 1.27 1.27)
			)
			(justify right bottom)
		)
	)
	(label "SDIO.D0"
		(at 170.18 214.63 180)
		(effects
			(font
				(size 1.27 1.27)
			)
			(justify right bottom)
		)
	)
	(label "SDIO.D1"
		(at 170.18 217.17 180)
		(effects
			(font
				(size 1.27 1.27)
			)
			(justify right bottom)
		)
	)
	(label "NVMe.TX1_N"
		(at 148.59 86.36 180)
		(effects
			(font
				(size 1.27 1.27)
			)
			(justify right bottom)
		)
	)
	(label "SDIO.D2"
		(at 170.18 199.39 180)
		(effects
			(font
				(size 1.27 1.27)
			)
			(justify right bottom)
		)
	)
	(label "SDIO.D0"
		(at 177.8 214.63 0)
		(effects
			(font
				(size 1.27 1.27)
			)
			(justify left bottom)
		)
	)
	(label "SDIO.D2"
		(at 177.8 199.39 0)
		(effects
			(font
				(size 1.27 1.27)
			)
			(justify left bottom)
		)
	)
	(label "SDIO.D3"
		(at 177.8 201.93 0)
		(effects
			(font
				(size 1.27 1.27)
			)
			(justify left bottom)
		)
	)
	(label "NVMe.TX3_N"
		(at 148.59 116.84 180)
		(effects
			(font
				(size 1.27 1.27)
			)
			(justify right bottom)
		)
	)
	(label "NVMe.CLK_P"
		(at 148.59 59.69 180)
		(effects
			(font
				(size 1.27 1.27)
			)
			(justify right bottom)
		)
	)
	(label "NVMe.TX0_P"
		(at 148.59 68.58 180)
		(effects
			(font
				(size 1.27 1.27)
			)
			(justify right bottom)
		)
	)
	(label "NVMe.RX3_N"
		(at 148.59 124.46 180)
		(effects
			(font
				(size 1.27 1.27)
			)
			(justify right bottom)
		)
	)
	(label "SDIO.D3"
		(at 170.18 201.93 180)
		(effects
			(font
				(size 1.27 1.27)
			)
			(justify right bottom)
		)
	)
	(label "SDIO.CMD"
		(at 170.18 204.47 180)
		(effects
			(font
				(size 1.27 1.27)
			)
			(justify right bottom)
		)
	)
	(label "SDIO.CLK"
		(at 170.18 209.55 180)
		(effects
			(font
				(size 1.27 1.27)
			)
			(justify right bottom)
		)
	)
	(label "SDIO.CD"
		(at 170.18 196.85 180)
		(effects
			(font
				(size 1.27 1.27)
			)
			(justify right bottom)
		)
	)
	(label "NVMe.RX3_P"
		(at 148.59 121.92 180)
		(effects
			(font
				(size 1.27 1.27)
			)
			(justify right bottom)
		)
	)
	(label "NVMe.TX3_P"
		(at 148.59 114.3 180)
		(effects
			(font
				(size 1.27 1.27)
			)
			(justify right bottom)
		)
	)
	(label "SDIO.CLK"
		(at 177.8 209.55 0)
		(effects
			(font
				(size 1.27 1.27)
			)
			(justify left bottom)
		)
	)
	(label "SDIO.CD"
		(at 177.8 222.25 0)
		(effects
			(font
				(size 1.27 1.27)
			)
			(justify left bottom)
		)
	)
	(label "SDIO.D1"
		(at 177.8 217.17 0)
		(effects
			(font
				(size 1.27 1.27)
			)
			(justify left bottom)
		)
	)
	(label "NVMe.RX0_N"
		(at 148.59 78.74 180)
		(effects
			(font
				(size 1.27 1.27)
			)
			(justify right bottom)
		)
	)
	(global_label "3V3_SSD"
		(shape input)
		(at 153.67 35.56 180)
		(fields_autoplaced yes)
		(effects
			(font
				(size 1.27 1.27)
			)
			(justify right)
		)
		(property "Intersheetrefs" "${INTERSHEET_REFS}"
			(at 143.1815 35.6394 0)
			(effects
				(font
					(size 1.27 1.27)
				)
				(justify right)
				(hide yes)
			)
		)
	)
	(global_label "3V3_SSD"
		(shape input)
		(at 267.97 38.1 0)
		(fields_autoplaced yes)
		(effects
			(font
				(size 1.27 1.27)
			)
			(justify left)
		)
		(property "Intersheetrefs" "${INTERSHEET_REFS}"
			(at 278.4585 38.0206 0)
			(effects
				(font
					(size 1.27 1.27)
				)
				(justify left)
				(hide yes)
			)
		)
	)
	(global_label "3V3_SSD"
		(shape input)
		(at 205.74 86.36 0)
		(fields_autoplaced yes)
		(effects
			(font
				(size 1.27 1.27)
			)
			(justify left)
		)
		(property "Intersheetrefs" "${INTERSHEET_REFS}"
			(at 216.2285 86.2806 0)
			(effects
				(font
					(size 1.27 1.27)
				)
				(justify left)
				(hide yes)
			)
		)
	)
	(hierarchical_label "NVMe{PCIe}"
		(shape bidirectional)
		(at 124.46 39.37 180)
		(effects
			(font
				(size 1.27 1.27)
			)
			(justify right)
		)
	)
	(hierarchical_label "SDIO{SDIO}"
		(shape bidirectional)
		(at 168.91 184.15 180)
		(effects
			(font
				(size 1.27 1.27)
			)
			(justify right)
		)
	)
	(symbol
		(lib_id "antmicropower:GND")
		(at 220.98 62.23 0)
		(unit 1)
		(exclude_from_sim no)
		(in_bom yes)
		(on_board yes)
		(dnp no)
		(fields_autoplaced yes)
		(property "Reference" "#PWR0506"
			(at 229.87 64.77 0)
			(effects
				(font
					(size 1.27 1.27)
					(thickness 0.15)
				)
				(justify left bottom)
				(hide yes)
			)
		)
		(property "Value" "GND"
			(at 220.98 67.31 0)
			(effects
				(font
					(size 1.27 1.27)
					(thickness 0.15)
				)
			)
		)
		(property "Footprint" ""
			(at 229.87 69.85 0)
			(effects
				(font
					(size 1.27 1.27)
					(thickness 0.15)
				)
				(justify left bottom)
				(hide yes)
			)
		)
		(property "Datasheet" ""
			(at 229.87 74.93 0)
			(effects
				(font
					(size 1.27 1.27)
					(thickness 0.15)
				)
				(justify left bottom)
				(hide yes)
			)
		)
		(property "Description" ""
			(at 220.98 62.23 0)
			(effects
				(font
					(size 1.27 1.27)
				)
				(hide yes)
			)
		)
		(property "Author" "Antmicro"
			(at 229.87 69.85 0)
			(effects
				(font
					(size 1.27 1.27)
					(thickness 0.15)
				)
				(justify left bottom)
				(hide yes)
			)
		)
		(property "License" "Apache-2.0"
			(at 229.87 72.39 0)
			(effects
				(font
					(size 1.27 1.27)
					(thickness 0.15)
				)
				(justify left bottom)
				(hide yes)
			)
		)
		(pin "1"
		)
		(instances
			(project "cm4-baseboard"
				(path ""
					(reference "#PWR0506")
					(unit 1)
				)
			)
		)
	)
	(symbol
		(lib_id "antmicropower:GND")
		(at 238.76 62.23 0)
		(unit 1)
		(exclude_from_sim no)
		(in_bom yes)
		(on_board yes)
		(dnp no)
		(fields_autoplaced yes)
		(property "Reference" "#PWR0510"
			(at 247.65 64.77 0)
			(effects
				(font
					(size 1.27 1.27)
					(thickness 0.15)
				)
				(justify left bottom)
				(hide yes)
			)
		)
		(property "Value" "GND"
			(at 238.76 67.31 0)
			(effects
				(font
					(size 1.27 1.27)
					(thickness 0.15)
				)
			)
		)
		(property "Footprint" ""
			(at 247.65 69.85 0)
			(effects
				(font
					(size 1.27 1.27)
					(thickness 0.15)
				)
				(justify left bottom)
				(hide yes)
			)
		)
		(property "Datasheet" ""
			(at 247.65 74.93 0)
			(effects
				(font
					(size 1.27 1.27)
					(thickness 0.15)
				)
				(justify left bottom)
				(hide yes)
			)
		)
		(property "Description" ""
			(at 238.76 62.23 0)
			(effects
				(font
					(size 1.27 1.27)
				)
				(hide yes)
			)
		)
		(property "Author" "Antmicro"
			(at 247.65 69.85 0)
			(effects
				(font
					(size 1.27 1.27)
					(thickness 0.15)
				)
				(justify left bottom)
				(hide yes)
			)
		)
		(property "License" "Apache-2.0"
			(at 247.65 72.39 0)
			(effects
				(font
					(size 1.27 1.27)
					(thickness 0.15)
				)
				(justify left bottom)
				(hide yes)
			)
		)
		(pin "1"
		)
		(instances
			(project "cm4-baseboard"
				(path ""
					(reference "#PWR0510")
					(unit 1)
				)
			)
		)
	)
	(symbol
		(lib_id "antmicropower:GND")
		(at 256.54 62.23 0)
		(unit 1)
		(exclude_from_sim no)
		(in_bom yes)
		(on_board yes)
		(dnp no)
		(fields_autoplaced yes)
		(property "Reference" "#PWR0511"
			(at 265.43 64.77 0)
			(effects
				(font
					(size 1.27 1.27)
					(thickness 0.15)
				)
				(justify left bottom)
				(hide yes)
			)
		)
		(property "Value" "GND"
			(at 256.54 67.31 0)
			(effects
				(font
					(size 1.27 1.27)
					(thickness 0.15)
				)
			)
		)
		(property "Footprint" ""
			(at 265.43 69.85 0)
			(effects
				(font
					(size 1.27 1.27)
					(thickness 0.15)
				)
				(justify left bottom)
				(hide yes)
			)
		)
		(property "Datasheet" ""
			(at 265.43 74.93 0)
			(effects
				(font
					(size 1.27 1.27)
					(thickness 0.15)
				)
				(justify left bottom)
				(hide yes)
			)
		)
		(property "Description" ""
			(at 256.54 62.23 0)
			(effects
				(font
					(size 1.27 1.27)
				)
				(hide yes)
			)
		)
		(property "Author" "Antmicro"
			(at 265.43 69.85 0)
			(effects
				(font
					(size 1.27 1.27)
					(thickness 0.15)
				)
				(justify left bottom)
				(hide yes)
			)
		)
		(property "License" "Apache-2.0"
			(at 265.43 72.39 0)
			(effects
				(font
					(size 1.27 1.27)
					(thickness 0.15)
				)
				(justify left bottom)
				(hide yes)
			)
		)
		(pin "1"
		)
		(instances
			(project "cm4-baseboard"
				(path ""
					(reference "#PWR0511")
					(unit 1)
				)
			)
		)
	)
	(symbol
		(lib_id "antmicroResistors0402:R_470R_0402")
		(at 205.74 93.98 270)
		(mirror x)
		(unit 1)
		(exclude_from_sim no)
		(in_bom yes)
		(on_board yes)
		(dnp no)
		(fields_autoplaced yes)
		(property "Reference" "R510"
			(at 208.28 90.1699 90)
			(effects
				(font
					(size 1.27 1.27)
				)
				(justify left)
			)
		)
		(property "Value" "R_470R_0402"
			(at 193.04 73.66 0)
			(effects
				(font
					(size 1.27 1.27)
					(thickness 0.15)
				)
				(justify left bottom)
				(hide yes)
			)
		)
		(property "Footprint" "antmicro-footprints:R_0402_1005Metric"
			(at 190.5 73.66 0)
			(effects
				(font
					(size 1.27 1.27)
					(thickness 0.15)
				)
				(justify left bottom)
				(hide yes)
			)
		)
		(property "Datasheet" "https://www.bourns.com/docs/product-datasheets/cr.pdf"
			(at 187.96 73.66 0)
			(effects
				(font
					(size 1.27 1.27)
					(thickness 0.15)
				)
				(justify left bottom)
				(hide yes)
			)
		)
		(property "Description" ""
			(at 205.74 93.98 0)
			(effects
				(font
					(size 1.27 1.27)
				)
				(hide yes)
			)
		)
		(property "Manufacturer" "Bourns"
			(at 182.88 73.66 0)
			(effects
				(font
					(size 1.27 1.27)
					(thickness 0.15)
				)
				(justify left bottom)
				(hide yes)
			)
		)
		(property "MPN" "CR0402-FX-4700GLF"
			(at 185.42 73.66 0)
			(effects
				(font
					(size 1.27 1.27)
					(thickness 0.15)
				)
				(justify left bottom)
				(hide yes)
			)
		)
		(property "Val" "470R"
			(at 208.28 92.7099 90)
			(effects
				(font
					(size 1.27 1.27)
					(thickness 0.15)
				)
				(justify left)
			)
		)
		(property "License" "Apache-2.0"
			(at 180.34 73.66 0)
			(effects
				(font
					(size 1.27 1.27)
					(thickness 0.15)
				)
				(justify left bottom)
				(hide yes)
			)
		)
		(property "Author" "Antmicro"
			(at 177.8 73.66 0)
			(effects
				(font
					(size 1.27 1.27)
					(thickness 0.15)
				)
				(justify left bottom)
				(hide yes)
			)
		)
		(property "Tolerance" "1%"
			(at 195.58 73.66 0)
			(effects
				(font
					(size 1.27 1.27)
				)
				(justify left bottom)
				(hide yes)
			)
		)
		(pin "1"
		)
		(pin "2"
		)
		(instances
			(project "cm4-baseboard"
				(path ""
					(reference "R510")
					(unit 1)
				)
			)
		)
	)
	(symbol
		(lib_id "antmicroCapacitors0402:C_1u_0402")
		(at 275.59 198.12 90)
		(unit 1)
		(exclude_from_sim no)
		(in_bom yes)
		(on_board yes)
		(dnp no)
		(fields_autoplaced yes)
		(property "Reference" "C507"
			(at 278.13 194.3036 90)
			(effects
				(font
					(size 1.27 1.27)
					(thickness 0.15)
				)
				(justify right)
			)
		)
		(property "Value" "C_1u_0402"
			(at 285.75 177.8 0)
			(effects
				(font
					(size 1.27 1.27)
					(thickness 0.15)
				)
				(justify left bottom)
				(hide yes)
			)
		)
		(property "Footprint" "antmicro-footprints:C_0402_1005Metric"
			(at 288.29 177.8 0)
			(effects
				(font
					(size 1.27 1.27)
					(thickness 0.15)
				)
				(justify left bottom)
				(hide yes)
			)
		)
		(property "Datasheet" "https://product.tdk.com/en/search/capacitor/ceramic/mlcc/info?part_no=C1005X6S1A105K050BC"
			(at 290.83 177.8 0)
			(effects
				(font
					(size 1.27 1.27)
					(thickness 0.15)
				)
				(justify left bottom)
				(hide yes)
			)
		)
		(property "Description" ""
			(at 275.59 198.12 0)
			(effects
				(font
					(size 1.27 1.27)
				)
				(hide yes)
			)
		)
		(property "Manufacturer" "TDK"
			(at 295.91 177.8 0)
			(effects
				(font
					(size 1.27 1.27)
					(thickness 0.15)
				)
				(justify left bottom)
				(hide yes)
			)
		)
		(property "MPN" "C1005X6S1A105K050BC"
			(at 293.37 177.8 0)
			(effects
				(font
					(size 1.27 1.27)
					(thickness 0.15)
				)
				(justify left bottom)
				(hide yes)
			)
		)
		(property "Val" "1u"
			(at 278.13 196.8436 90)
			(effects
				(font
					(size 1.27 1.27)
					(thickness 0.15)
				)
				(justify right)
			)
		)
		(property "License" "Apache-2.0"
			(at 298.45 177.8 0)
			(effects
				(font
					(size 1.27 1.27)
					(thickness 0.15)
				)
				(justify left bottom)
				(hide yes)
			)
		)
		(property "Author" "Antmicro"
			(at 300.99 177.8 0)
			(effects
				(font
					(size 1.27 1.27)
					(thickness 0.15)
				)
				(justify left bottom)
				(hide yes)
			)
		)
		(property "Voltage" ""
			(at 303.53 177.8 0)
			(effects
				(font
					(size 1.27 1.27)
				)
				(justify left bottom)
				(hide yes)
			)
		)
		(property "Dielectric" ""
			(at 306.07 177.8 0)
			(effects
				(font
					(size 1.27 1.27)
				)
				(justify left bottom)
				(hide yes)
			)
		)
		(pin "1"
		)
		(pin "2"
		)
		(instances
			(project "cm4-baseboard"
				(path ""
					(reference "C507")
					(unit 1)
				)
			)
		)
	)
	(symbol
		(lib_id "antmicropower:+3V3")
		(at 205.74 185.42 0)
		(unit 1)
		(exclude_from_sim no)
		(in_bom yes)
		(on_board yes)
		(dnp no)
		(fields_autoplaced yes)
		(property "Reference" "#PWR0504"
			(at 220.98 187.96 0)
			(effects
				(font
					(size 1.27 1.27)
					(thickness 0.15)
				)
				(justify left bottom)
				(hide yes)
			)
		)
		(property "Value" "+3V3"
			(at 205.74 180.34 0)
			(effects
				(font
					(size 1.27 1.27)
					(thickness 0.15)
				)
			)
		)
		(property "Footprint" ""
			(at 220.98 193.04 0)
			(effects
				(font
					(size 1.27 1.27)
					(thickness 0.15)
				)
				(justify left bottom)
				(hide yes)
			)
		)
		(property "Datasheet" ""
			(at 220.98 195.58 0)
			(effects
				(font
					(size 1.27 1.27)
					(thickness 0.15)
				)
				(justify left bottom)
				(hide yes)
			)
		)
		(property "Description" ""
			(at 205.74 185.42 0)
			(effects
				(font
					(size 1.27 1.27)
				)
				(hide yes)
			)
		)
		(property "Author" "Antmicro"
			(at 220.98 193.04 0)
			(effects
				(font
					(size 1.27 1.27)
					(thickness 0.15)
				)
				(justify left bottom)
				(hide yes)
			)
		)
		(property "License" "Apache-2.0"
			(at 220.98 195.58 0)
			(effects
				(font
					(size 1.27 1.27)
					(thickness 0.15)
				)
				(justify left bottom)
				(hide yes)
			)
		)
		(pin "1"
		)
		(instances
			(project "cm4-baseboard"
				(path ""
					(reference "#PWR0504")
					(unit 1)
				)
			)
		)
	)
	(symbol
		(lib_id "antmicroModules:Mech_M2_2280_H2.5mm")
		(at 234.95 121.92 180)
		(unit 1)
		(exclude_from_sim no)
		(in_bom no)
		(on_board yes)
		(dnp yes)
		(fields_autoplaced yes)
		(property "Reference" "M501"
			(at 229.87 124.46 0)
			(effects
				(font
					(size 1.27 1.27)
				)
			)
		)
		(property "Value" "Mech_M2_2280_H2.5mm"
			(at 229.87 127 0)
			(effects
				(font
					(size 1.27 1.27)
					(thickness 0.15)
				)
			)
		)
		(property "Footprint" "antmicro-footprints:Mech_M2_2280_H2.5mm"
			(at 209.55 116.84 0)
			(effects
				(font
					(size 1.27 1.27)
					(thickness 0.15)
				)
				(justify left bottom)
				(hide yes)
			)
		)
		(property "Datasheet" ""
			(at 209.55 114.3 0)
			(effects
				(font
					(size 1.27 1.27)
					(thickness 0.15)
				)
				(justify left bottom)
				(hide yes)
			)
		)
		(property "Description" "Mechanical model for M2 2280 2.5mm module"
			(at 234.95 121.92 0)
			(effects
				(font
					(size 1.27 1.27)
				)
				(hide yes)
			)
		)
		(property "Manufacturer" ""
			(at 234.95 121.92 0)
			(effects
				(font
					(size 1.27 1.27)
				)
				(hide yes)
			)
		)
		(property "MPN" ""
			(at 234.95 121.92 0)
			(effects
				(font
					(size 1.27 1.27)
				)
				(hide yes)
			)
		)
		(property "Author" "Antmicro"
			(at 209.55 111.76 0)
			(effects
				(font
					(size 1.27 1.27)
					(thickness 0.15)
				)
				(justify left bottom)
				(hide yes)
			)
		)
		(property "License" "Apache-2.0"
			(at 209.55 109.22 0)
			(effects
				(font
					(size 1.27 1.27)
					(thickness 0.15)
				)
				(justify left bottom)
				(hide yes)
			)
		)
		(instances
			(project "cm4-baseboard"
				(path ""
					(reference "M501")
					(unit 1)
				)
			)
		)
	)
	(symbol
		(lib_id "antmicroResistors0402:R_470R_0402")
		(at 191.77 222.25 180)
		(unit 1)
		(exclude_from_sim no)
		(in_bom yes)
		(on_board yes)
		(dnp no)
		(fields_autoplaced yes)
		(property "Reference" "R505"
			(at 189.23 226.06 0)
			(effects
				(font
					(size 1.27 1.27)
				)
			)
		)
		(property "Value" "R_470R_0402"
			(at 171.45 209.55 0)
			(effects
				(font
					(size 1.27 1.27)
					(thickness 0.15)
				)
				(justify left bottom)
				(hide yes)
			)
		)
		(property "Footprint" "antmicro-footprints:R_0402_1005Metric"
			(at 171.45 207.01 0)
			(effects
				(font
					(size 1.27 1.27)
					(thickness 0.15)
				)
				(justify left bottom)
				(hide yes)
			)
		)
		(property "Datasheet" "https://www.bourns.com/docs/product-datasheets/cr.pdf"
			(at 171.45 204.47 0)
			(effects
				(font
					(size 1.27 1.27)
					(thickness 0.15)
				)
				(justify left bottom)
				(hide yes)
			)
		)
		(property "Description" ""
			(at 191.77 222.25 0)
			(effects
				(font
					(size 1.27 1.27)
				)
				(hide yes)
			)
		)
		(property "Manufacturer" "Bourns"
			(at 171.45 199.39 0)
			(effects
				(font
					(size 1.27 1.27)
					(thickness 0.15)
				)
				(justify left bottom)
				(hide yes)
			)
		)
		(property "MPN" "CR0402-FX-4700GLF"
			(at 171.45 201.93 0)
			(effects
				(font
					(size 1.27 1.27)
					(thickness 0.15)
				)
				(justify left bottom)
				(hide yes)
			)
		)
		(property "Val" "470R"
			(at 189.23 228.6 0)
			(effects
				(font
					(size 1.27 1.27)
					(thickness 0.15)
				)
			)
		)
		(property "License" "Apache-2.0"
			(at 171.45 196.85 0)
			(effects
				(font
					(size 1.27 1.27)
					(thickness 0.15)
				)
				(justify left bottom)
				(hide yes)
			)
		)
		(property "Author" "Antmicro"
			(at 171.45 194.31 0)
			(effects
				(font
					(size 1.27 1.27)
					(thickness 0.15)
				)
				(justify left bottom)
				(hide yes)
			)
		)
		(property "Tolerance" "1%"
			(at 171.45 212.09 0)
			(effects
				(font
					(size 1.27 1.27)
				)
				(justify left bottom)
				(hide yes)
			)
		)
		(pin "1"
		)
		(pin "2"
		)
		(instances
			(project "cm4-baseboard"
				(path ""
					(reference "R505")
					(unit 1)
				)
			)
		)
	)
	(symbol
		(lib_id "antmicropower:+3V3")
		(at 285.75 191.77 0)
		(unit 1)
		(exclude_from_sim no)
		(in_bom yes)
		(on_board yes)
		(dnp no)
		(property "Reference" "#PWR0501"
			(at 300.99 191.77 0)
			(effects
				(font
					(size 1.27 1.27)
					(thickness 0.15)
				)
				(justify left bottom)
				(hide yes)
			)
		)
		(property "Value" "+3V3"
			(at 285.75 186.69 0)
			(effects
				(font
					(size 1.27 1.27)
					(thickness 0.15)
				)
			)
		)
		(property "Footprint" ""
			(at 300.99 199.39 0)
			(effects
				(font
					(size 1.27 1.27)
					(thickness 0.15)
				)
				(justify left bottom)
				(hide yes)
			)
		)
		(property "Datasheet" ""
			(at 300.99 201.93 0)
			(effects
				(font
					(size 1.27 1.27)
					(thickness 0.15)
				)
				(justify left bottom)
				(hide yes)
			)
		)
		(property "Description" ""
			(at 285.75 191.77 0)
			(effects
				(font
					(size 1.27 1.27)
				)
				(hide yes)
			)
		)
		(property "Author" "Antmicro"
			(at 300.99 194.31 0)
			(effects
				(font
					(size 1.27 1.27)
					(thickness 0.15)
				)
				(justify left bottom)
				(hide yes)
			)
		)
		(property "License" "Apache-2.0"
			(at 300.99 196.85 0)
			(effects
				(font
					(size 1.27 1.27)
					(thickness 0.15)
				)
				(justify left bottom)
				(hide yes)
			)
		)
		(pin "1"
		)
		(instances
			(project "cm4-baseboard"
				(path ""
					(reference "#PWR0501")
					(unit 1)
				)
			)
		)
	)
	(symbol
		(lib_id "antmicroResistors0402:R_10k_0402")
		(at 195.58 191.77 270)
		(unit 1)
		(exclude_from_sim no)
		(in_bom yes)
		(on_board yes)
		(dnp no)
		(property "Reference" "R506"
			(at 196.85 193.0401 90)
			(effects
				(font
					(size 1.27 1.27)
					(thickness 0.15)
				)
				(justify left)
			)
		)
		(property "Value" "R_10k_0402"
			(at 182.88 212.09 0)
			(effects
				(font
					(size 1.27 1.27)
					(thickness 0.15)
				)
				(justify left bottom)
				(hide yes)
			)
		)
		(property "Footprint" "antmicro-footprints:R_0402_1005Metric"
			(at 180.34 212.09 0)
			(effects
				(font
					(size 1.27 1.27)
					(thickness 0.15)
				)
				(justify left bottom)
				(hide yes)
			)
		)
		(property "Datasheet" "https://www.bourns.com/docs/product-datasheets/cr.pdf"
			(at 177.8 212.09 0)
			(effects
				(font
					(size 1.27 1.27)
					(thickness 0.15)
				)
				(justify left bottom)
				(hide yes)
			)
		)
		(property "Description" ""
			(at 195.58 191.77 0)
			(effects
				(font
					(size 1.27 1.27)
				)
				(hide yes)
			)
		)
		(property "Manufacturer" "Bourns"
			(at 172.72 212.09 0)
			(effects
				(font
					(size 1.27 1.27)
					(thickness 0.15)
				)
				(justify left bottom)
				(hide yes)
			)
		)
		(property "MPN" "CR0402-FX-1002GLF"
			(at 175.26 212.09 0)
			(effects
				(font
					(size 1.27 1.27)
					(thickness 0.15)
				)
				(justify left bottom)
				(hide yes)
			)
		)
		(property "Val" "10k"
			(at 196.85 195.5801 90)
			(effects
				(font
					(size 1.27 1.27)
					(thickness 0.15)
				)
				(justify left)
			)
		)
		(property "License" "Apache-2.0"
			(at 170.18 212.09 0)
			(effects
				(font
					(size 1.27 1.27)
					(thickness 0.15)
				)
				(justify left bottom)
				(hide yes)
			)
		)
		(property "Author" "Antmicro"
			(at 167.64 212.09 0)
			(effects
				(font
					(size 1.27 1.27)
					(thickness 0.15)
				)
				(justify left bottom)
				(hide yes)
			)
		)
		(property "Tolerance" "1%"
			(at 185.42 212.09 0)
			(effects
				(font
					(size 1.27 1.27)
				)
				(justify left bottom)
				(hide yes)
			)
		)
		(pin "1"
		)
		(pin "2"
		)
		(instances
			(project "cm4-baseboard"
				(path ""
					(reference "R506")
					(unit 1)
				)
			)
		)
	)
	(symbol
		(lib_id "antmicroResistors0402:R_10k_0402")
		(at 203.2 191.77 270)
		(unit 1)
		(exclude_from_sim no)
		(in_bom yes)
		(on_board yes)
		(dnp no)
		(property "Reference" "R507"
			(at 204.47 193.04 90)
			(effects
				(font
					(size 1.27 1.27)
					(thickness 0.15)
				)
				(justify left)
			)
		)
		(property "Value" "R_10k_0402"
			(at 190.5 212.09 0)
			(effects
				(font
					(size 1.27 1.27)
					(thickness 0.15)
				)
				(justify left bottom)
				(hide yes)
			)
		)
		(property "Footprint" "antmicro-footprints:R_0402_1005Metric"
			(at 187.96 212.09 0)
			(effects
				(font
					(size 1.27 1.27)
					(thickness 0.15)
				)
				(justify left bottom)
				(hide yes)
			)
		)
		(property "Datasheet" "https://www.bourns.com/docs/product-datasheets/cr.pdf"
			(at 185.42 212.09 0)
			(effects
				(font
					(size 1.27 1.27)
					(thickness 0.15)
				)
				(justify left bottom)
				(hide yes)
			)
		)
		(property "Description" ""
			(at 203.2 191.77 0)
			(effects
				(font
					(size 1.27 1.27)
				)
				(hide yes)
			)
		)
		(property "Manufacturer" "Bourns"
			(at 180.34 212.09 0)
			(effects
				(font
					(size 1.27 1.27)
					(thickness 0.15)
				)
				(justify left bottom)
				(hide yes)
			)
		)
		(property "MPN" "CR0402-FX-1002GLF"
			(at 182.88 212.09 0)
			(effects
				(font
					(size 1.27 1.27)
					(thickness 0.15)
				)
				(justify left bottom)
				(hide yes)
			)
		)
		(property "Val" "10k"
			(at 204.47 195.58 90)
			(effects
				(font
					(size 1.27 1.27)
					(thickness 0.15)
				)
				(justify left)
			)
		)
		(property "License" "Apache-2.0"
			(at 177.8 212.09 0)
			(effects
				(font
					(size 1.27 1.27)
					(thickness 0.15)
				)
				(justify left bottom)
				(hide yes)
			)
		)
		(property "Author" "Antmicro"
			(at 175.26 212.09 0)
			(effects
				(font
					(size 1.27 1.27)
					(thickness 0.15)
				)
				(justify left bottom)
				(hide yes)
			)
		)
		(property "Tolerance" "1%"
			(at 193.04 212.09 0)
			(effects
				(font
					(size 1.27 1.27)
				)
				(justify left bottom)
				(hide yes)
			)
		)
		(pin "1"
		)
		(pin "2"
		)
		(instances
			(project "cm4-baseboard"
				(path ""
					(reference "R507")
					(unit 1)
				)
			)
		)
	)
	(symbol
		(lib_id "antmicropower:GND")
		(at 275.59 199.39 0)
		(unit 1)
		(exclude_from_sim no)
		(in_bom yes)
		(on_board yes)
		(dnp no)
		(property "Reference" "#PWR0515"
			(at 284.48 201.93 0)
			(effects
				(font
					(size 1.27 1.27)
					(thickness 0.15)
				)
				(justify left bottom)
				(hide yes)
			)
		)
		(property "Value" "GND"
			(at 275.59 204.47 0)
			(effects
				(font
					(size 1.27 1.27)
					(thickness 0.15)
				)
			)
		)
		(property "Footprint" ""
			(at 284.48 207.01 0)
			(effects
				(font
					(size 1.27 1.27)
					(thickness 0.15)
				)
				(justify left bottom)
				(hide yes)
			)
		)
		(property "Datasheet" ""
			(at 284.48 212.09 0)
			(effects
				(font
					(size 1.27 1.27)
					(thickness 0.15)
				)
				(justify left bottom)
				(hide yes)
			)
		)
		(property "Description" ""
			(at 275.59 199.39 0)
			(effects
				(font
					(size 1.27 1.27)
				)
				(hide yes)
			)
		)
		(property "Author" "Antmicro"
			(at 284.48 207.01 0)
			(effects
				(font
					(size 1.27 1.27)
					(thickness 0.15)
				)
				(justify left bottom)
				(hide yes)
			)
		)
		(property "License" "Apache-2.0"
			(at 284.48 209.55 0)
			(effects
				(font
					(size 1.27 1.27)
					(thickness 0.15)
				)
				(justify left bottom)
				(hide yes)
			)
		)
		(pin "1"
		)
		(instances
			(project "cm4-baseboard"
				(path ""
					(reference "#PWR0515")
					(unit 1)
				)
			)
		)
	)
	(symbol
		(lib_id "antmicroCapacitors0402:C_1u_0402")
		(at 260.35 54.61 90)
		(unit 1)
		(exclude_from_sim no)
		(in_bom yes)
		(on_board yes)
		(dnp no)
		(property "Reference" "C506"
			(at 260.35 49.53 90)
			(effects
				(font
					(size 1.27 1.27)
				)
				(justify left)
			)
		)
		(property "Value" "C_1u_0402"
			(at 264.16 54.61 0)
			(effects
				(font
					(size 1.27 1.27)
				)
				(justify left bottom)
				(hide yes)
			)
		)
		(property "Footprint" "antmicro-footprints:C_0402_1005Metric"
			(at 255.27 49.53 0)
			(effects
				(font
					(size 1.524 1.524)
				)
				(justify left bottom)
				(hide yes)
			)
		)
		(property "Datasheet" "https://product.tdk.com/en/search/capacitor/ceramic/mlcc/info?part_no=C1005X6S1A105K050BC"
			(at 260.35 54.61 0)
			(effects
				(font
					(size 1.27 1.27)
				)
				(justify left bottom)
				(hide yes)
			)
		)
		(property "Description" ""
			(at 260.35 54.61 0)
			(effects
				(font
					(size 1.27 1.27)
				)
				(hide yes)
			)
		)
		(property "Manufacturer" "TDK"
			(at 250.19 49.53 0)
			(effects
				(font
					(size 1.524 1.524)
				)
				(justify left bottom)
				(hide yes)
			)
		)
		(property "MPN" "C1005X6S1A105K050BC"
			(at 252.73 49.53 0)
			(effects
				(font
					(size 1.524 1.524)
				)
				(justify left bottom)
				(hide yes)
			)
		)
		(property "Val" "1u"
			(at 259.08 54.61 90)
			(effects
				(font
					(size 1.27 1.27)
				)
				(justify left)
			)
		)
		(property "License" "Apache-2.0"
			(at 283.21 34.29 0)
			(effects
				(font
					(size 1.27 1.27)
					(thickness 0.15)
				)
				(justify left bottom)
				(hide yes)
			)
		)
		(property "Author" "Antmicro"
			(at 285.75 34.29 0)
			(effects
				(font
					(size 1.27 1.27)
					(thickness 0.15)
				)
				(justify left bottom)
				(hide yes)
			)
		)
		(property "Voltage" ""
			(at 288.29 34.29 0)
			(effects
				(font
					(size 1.27 1.27)
				)
				(justify left bottom)
				(hide yes)
			)
		)
		(property "Dielectric" ""
			(at 290.83 34.29 0)
			(effects
				(font
					(size 1.27 1.27)
				)
				(justify left bottom)
				(hide yes)
			)
		)
		(pin "1"
		)
		(pin "2"
		)
		(instances
			(project "cm4-baseboard"
				(path ""
					(reference "C506")
					(unit 1)
				)
			)
		)
	)
	(symbol
		(lib_id "antmicroResistors0402:R_470R_0402")
		(at 234.95 196.85 90)
		(unit 1)
		(exclude_from_sim no)
		(in_bom yes)
		(on_board yes)
		(dnp no)
		(property "Reference" "R512"
			(at 236.22 193.04 90)
			(effects
				(font
					(size 1.27 1.27)
				)
				(justify right)
			)
		)
		(property "Value" "R_470R_0402"
			(at 247.65 176.53 0)
			(effects
				(font
					(size 1.27 1.27)
					(thickness 0.15)
				)
				(justify left bottom)
				(hide yes)
			)
		)
		(property "Footprint" "antmicro-footprints:R_0402_1005Metric"
			(at 250.19 176.53 0)
			(effects
				(font
					(size 1.27 1.27)
					(thickness 0.15)
				)
				(justify left bottom)
				(hide yes)
			)
		)
		(property "Datasheet" "https://www.bourns.com/docs/product-datasheets/cr.pdf"
			(at 252.73 176.53 0)
			(effects
				(font
					(size 1.27 1.27)
					(thickness 0.15)
				)
				(justify left bottom)
				(hide yes)
			)
		)
		(property "Description" ""
			(at 234.95 196.85 0)
			(effects
				(font
					(size 1.27 1.27)
				)
				(hide yes)
			)
		)
		(property "Manufacturer" "Bourns"
			(at 257.81 176.53 0)
			(effects
				(font
					(size 1.27 1.27)
					(thickness 0.15)
				)
				(justify left bottom)
				(hide yes)
			)
		)
		(property "MPN" "CR0402-FX-4700GLF"
			(at 255.27 176.53 0)
			(effects
				(font
					(size 1.27 1.27)
					(thickness 0.15)
				)
				(justify left bottom)
				(hide yes)
			)
		)
		(property "Val" "470R"
			(at 236.22 195.58 90)
			(effects
				(font
					(size 1.27 1.27)
					(thickness 0.15)
				)
				(justify right)
			)
		)
		(property "License" "Apache-2.0"
			(at 260.35 176.53 0)
			(effects
				(font
					(size 1.27 1.27)
					(thickness 0.15)
				)
				(justify left bottom)
				(hide yes)
			)
		)
		(property "Author" "Antmicro"
			(at 262.89 176.53 0)
			(effects
				(font
					(size 1.27 1.27)
					(thickness 0.15)
				)
				(justify left bottom)
				(hide yes)
			)
		)
		(property "Tolerance" "1%"
			(at 245.11 176.53 0)
			(effects
				(font
					(size 1.27 1.27)
				)
				(justify left bottom)
				(hide yes)
			)
		)
		(pin "1"
		)
		(pin "2"
		)
		(instances
			(project "cm4-baseboard"
				(path ""
					(reference "R512")
					(unit 1)
				)
			)
		)
	)
	(symbol
		(lib_id "antmicropower:+3V3")
		(at 242.57 185.42 0)
		(unit 1)
		(exclude_from_sim no)
		(in_bom yes)
		(on_board yes)
		(dnp no)
		(fields_autoplaced yes)
		(property "Reference" "#PWR0508"
			(at 257.81 187.96 0)
			(effects
				(font
					(size 1.27 1.27)
					(thickness 0.15)
				)
				(justify left bottom)
				(hide yes)
			)
		)
		(property "Value" "+3V3"
			(at 242.57 180.34 0)
			(effects
				(font
					(size 1.27 1.27)
					(thickness 0.15)
				)
			)
		)
		(property "Footprint" ""
			(at 257.81 193.04 0)
			(effects
				(font
					(size 1.27 1.27)
					(thickness 0.15)
				)
				(justify left bottom)
				(hide yes)
			)
		)
		(property "Datasheet" ""
			(at 257.81 195.58 0)
			(effects
				(font
					(size 1.27 1.27)
					(thickness 0.15)
				)
				(justify left bottom)
				(hide yes)
			)
		)
		(property "Description" ""
			(at 242.57 185.42 0)
			(effects
				(font
					(size 1.27 1.27)
				)
				(hide yes)
			)
		)
		(property "Author" "Antmicro"
			(at 257.81 193.04 0)
			(effects
				(font
					(size 1.27 1.27)
					(thickness 0.15)
				)
				(justify left bottom)
				(hide yes)
			)
		)
		(property "License" "Apache-2.0"
			(at 257.81 195.58 0)
			(effects
				(font
					(size 1.27 1.27)
					(thickness 0.15)
				)
				(justify left bottom)
				(hide yes)
			)
		)
		(pin "1"
		)
		(instances
			(project "cm4-baseboard"
				(path ""
					(reference "#PWR0508")
					(unit 1)
				)
			)
		)
	)
	(symbol
		(lib_id "antmicroResistors0402:R_10k_0402")
		(at 162.56 41.91 90)
		(unit 1)
		(exclude_from_sim no)
		(in_bom yes)
		(on_board yes)
		(dnp no)
		(property "Reference" "R502"
			(at 161.29 38.1 90)
			(effects
				(font
					(size 1.27 1.27)
				)
				(justify left)
			)
		)
		(property "Value" "R_10k_0402"
			(at 166.37 41.91 0)
			(effects
				(font
					(size 1.27 1.27)
				)
				(justify left bottom)
				(hide yes)
			)
		)
		(property "Footprint" "antmicro-footprints:R_0402_1005Metric"
			(at 157.48 36.83 0)
			(effects
				(font
					(size 1.524 1.524)
				)
				(justify left bottom)
				(hide yes)
			)
		)
		(property "Datasheet" "https://www.bourns.com/docs/product-datasheets/cr.pdf"
			(at 162.56 41.91 0)
			(effects
				(font
					(size 1.27 1.27)
				)
				(justify left bottom)
				(hide yes)
			)
		)
		(property "Description" ""
			(at 162.56 41.91 0)
			(effects
				(font
					(size 1.27 1.27)
				)
				(hide yes)
			)
		)
		(property "Manufacturer" "Bourns"
			(at 152.4 36.83 0)
			(effects
				(font
					(size 1.524 1.524)
				)
				(justify left bottom)
				(hide yes)
			)
		)
		(property "MPN" "CR0402-FX-1002GLF"
			(at 154.94 36.83 0)
			(effects
				(font
					(size 1.524 1.524)
				)
				(justify left bottom)
				(hide yes)
			)
		)
		(property "Val" "10k"
			(at 161.29 40.64 90)
			(effects
				(font
					(size 1.27 1.27)
				)
				(justify left)
			)
		)
		(property "License" "Apache-2.0"
			(at 187.96 21.59 0)
			(effects
				(font
					(size 1.27 1.27)
					(thickness 0.15)
				)
				(justify left bottom)
				(hide yes)
			)
		)
		(property "Author" "Antmicro"
			(at 190.5 21.59 0)
			(effects
				(font
					(size 1.27 1.27)
					(thickness 0.15)
				)
				(justify left bottom)
				(hide yes)
			)
		)
		(property "Tolerance" "1%"
			(at 172.72 21.59 0)
			(effects
				(font
					(size 1.27 1.27)
				)
				(justify left bottom)
				(hide yes)
			)
		)
		(pin "1"
		)
		(pin "2"
		)
		(instances
			(project "cm4-baseboard"
				(path ""
					(reference "R502")
					(unit 1)
				)
			)
		)
	)
	(symbol
		(lib_id "antmicroResistors0402:R_10k_0402")
		(at 218.44 191.77 270)
		(unit 1)
		(exclude_from_sim no)
		(in_bom yes)
		(on_board yes)
		(dnp no)
		(property "Reference" "R509"
			(at 219.71 193.04 90)
			(effects
				(font
					(size 1.27 1.27)
					(thickness 0.15)
				)
				(justify left)
			)
		)
		(property "Value" "R_10k_0402"
			(at 205.74 212.09 0)
			(effects
				(font
					(size 1.27 1.27)
					(thickness 0.15)
				)
				(justify left bottom)
				(hide yes)
			)
		)
		(property "Footprint" "antmicro-footprints:R_0402_1005Metric"
			(at 203.2 212.09 0)
			(effects
				(font
					(size 1.27 1.27)
					(thickness 0.15)
				)
				(justify left bottom)
				(hide yes)
			)
		)
		(property "Datasheet" "https://www.bourns.com/docs/product-datasheets/cr.pdf"
			(at 200.66 212.09 0)
			(effects
				(font
					(size 1.27 1.27)
					(thickness 0.15)
				)
				(justify left bottom)
				(hide yes)
			)
		)
		(property "Description" ""
			(at 218.44 191.77 0)
			(effects
				(font
					(size 1.27 1.27)
				)
				(hide yes)
			)
		)
		(property "Manufacturer" "Bourns"
			(at 195.58 212.09 0)
			(effects
				(font
					(size 1.27 1.27)
					(thickness 0.15)
				)
				(justify left bottom)
				(hide yes)
			)
		)
		(property "MPN" "CR0402-FX-1002GLF"
			(at 198.12 212.09 0)
			(effects
				(font
					(size 1.27 1.27)
					(thickness 0.15)
				)
				(justify left bottom)
				(hide yes)
			)
		)
		(property "Val" "10k"
			(at 219.71 195.58 90)
			(effects
				(font
					(size 1.27 1.27)
					(thickness 0.15)
				)
				(justify left)
			)
		)
		(property "License" "Apache-2.0"
			(at 193.04 212.09 0)
			(effects
				(font
					(size 1.27 1.27)
					(thickness 0.15)
				)
				(justify left bottom)
				(hide yes)
			)
		)
		(property "Author" "Antmicro"
			(at 190.5 212.09 0)
			(effects
				(font
					(size 1.27 1.27)
					(thickness 0.15)
				)
				(justify left bottom)
				(hide yes)
			)
		)
		(property "Tolerance" "1%"
			(at 208.28 212.09 0)
			(effects
				(font
					(size 1.27 1.27)
				)
				(justify left bottom)
				(hide yes)
			)
		)
		(pin "1"
		)
		(pin "2"
		)
		(instances
			(project "cm4-baseboard"
				(path ""
					(reference "R509")
					(unit 1)
				)
			)
		)
	)
	(symbol
		(lib_id "antmicroCapacitors0402:C_10u_0402")
		(at 234.95 54.61 90)
		(unit 1)
		(exclude_from_sim no)
		(in_bom yes)
		(on_board yes)
		(dnp no)
		(property "Reference" "C503"
			(at 234.95 49.53 90)
			(effects
				(font
					(size 1.27 1.27)
					(thickness 0.15)
				)
				(justify left)
			)
		)
		(property "Value" "C_10u_0402"
			(at 245.11 34.29 0)
			(effects
				(font
					(size 1.27 1.27)
					(thickness 0.15)
				)
				(justify left bottom)
				(hide yes)
			)
		)
		(property "Footprint" "antmicro-footprints:C_0402_1005Metric"
			(at 247.65 34.29 0)
			(effects
				(font
					(size 1.27 1.27)
					(thickness 0.15)
				)
				(justify left bottom)
				(hide yes)
			)
		)
		(property "Datasheet" "https://www.yageo.com/en/Chart/Download/pdf/CC0402MRX5R5BB106"
			(at 250.19 34.29 0)
			(effects
				(font
					(size 1.27 1.27)
					(thickness 0.15)
				)
				(justify left bottom)
				(hide yes)
			)
		)
		(property "Description" ""
			(at 234.95 54.61 0)
			(effects
				(font
					(size 1.27 1.27)
				)
				(hide yes)
			)
		)
		(property "MPN" "CC0402MRX5R5BB106"
			(at 252.73 34.29 0)
			(effects
				(font
					(size 1.27 1.27)
					(thickness 0.15)
				)
				(justify left bottom)
				(hide yes)
			)
		)
		(property "Manufacturer" "YAGEO"
			(at 255.27 34.29 0)
			(effects
				(font
					(size 1.27 1.27)
					(thickness 0.15)
				)
				(justify left bottom)
				(hide yes)
			)
		)
		(property "License" "Apache-2.0"
			(at 257.81 34.29 0)
			(effects
				(font
					(size 1.27 1.27)
					(thickness 0.15)
				)
				(justify left bottom)
				(hide yes)
			)
		)
		(property "Author" "Antmicro"
			(at 260.35 34.29 0)
			(effects
				(font
					(size 1.27 1.27)
					(thickness 0.15)
				)
				(justify left bottom)
				(hide yes)
			)
		)
		(property "Val" "10u"
			(at 234.95 54.61 90)
			(effects
				(font
					(size 1.27 1.27)
					(thickness 0.15)
				)
				(justify left)
			)
		)
		(property "Voltage" ""
			(at 262.89 34.29 0)
			(effects
				(font
					(size 1.27 1.27)
				)
				(justify left bottom)
				(hide yes)
			)
		)
		(property "Dielectric" ""
			(at 265.43 34.29 0)
			(effects
				(font
					(size 1.27 1.27)
				)
				(justify left bottom)
				(hide yes)
			)
		)
		(pin "1"
		)
		(pin "2"
		)
		(instances
			(project "cm4-baseboard"
				(path ""
					(reference "C503")
					(unit 1)
				)
			)
		)
	)
	(symbol
		(lib_id "antmicropower:GND")
		(at 267.97 224.79 0)
		(unit 1)
		(exclude_from_sim no)
		(in_bom yes)
		(on_board yes)
		(dnp no)
		(fields_autoplaced yes)
		(property "Reference" "#PWR0512"
			(at 276.86 227.33 0)
			(effects
				(font
					(size 1.27 1.27)
					(thickness 0.15)
				)
				(justify left bottom)
				(hide yes)
			)
		)
		(property "Value" "GND"
			(at 265.9598 229.87 0)
			(effects
				(font
					(size 1.27 1.27)
					(thickness 0.15)
				)
				(justify left bottom)
			)
		)
		(property "Footprint" ""
			(at 276.86 232.41 0)
			(effects
				(font
					(size 1.27 1.27)
					(thickness 0.15)
				)
				(justify left bottom)
				(hide yes)
			)
		)
		(property "Datasheet" ""
			(at 276.86 237.49 0)
			(effects
				(font
					(size 1.27 1.27)
					(thickness 0.15)
				)
				(justify left bottom)
				(hide yes)
			)
		)
		(property "Description" ""
			(at 267.97 224.79 0)
			(effects
				(font
					(size 1.27 1.27)
				)
				(hide yes)
			)
		)
		(property "Author" "Antmicro"
			(at 276.86 232.41 0)
			(effects
				(font
					(size 1.27 1.27)
					(thickness 0.15)
				)
				(justify left bottom)
				(hide yes)
			)
		)
		(property "License" "Apache-2.0"
			(at 276.86 234.95 0)
			(effects
				(font
					(size 1.27 1.27)
					(thickness 0.15)
				)
				(justify left bottom)
				(hide yes)
			)
		)
		(pin "1"
		)
		(instances
			(project "cm4-baseboard"
				(path ""
					(reference "#PWR0512")
					(unit 1)
				)
			)
		)
	)
	(symbol
		(lib_id "antmicropower:GND")
		(at 151.13 208.28 0)
		(mirror y)
		(unit 1)
		(exclude_from_sim no)
		(in_bom yes)
		(on_board yes)
		(dnp no)
		(property "Reference" "#PWR0502"
			(at 142.24 210.82 0)
			(effects
				(font
					(size 1.27 1.27)
					(thickness 0.15)
				)
				(justify left bottom)
				(hide yes)
			)
		)
		(property "Value" "GND"
			(at 151.13 212.09 0)
			(effects
				(font
					(size 1.27 1.27)
					(thickness 0.15)
				)
			)
		)
		(property "Footprint" ""
			(at 142.24 215.9 0)
			(effects
				(font
					(size 1.27 1.27)
					(thickness 0.15)
				)
				(justify left bottom)
				(hide yes)
			)
		)
		(property "Datasheet" ""
			(at 142.24 220.98 0)
			(effects
				(font
					(size 1.27 1.27)
					(thickness 0.15)
				)
				(justify left bottom)
				(hide yes)
			)
		)
		(property "Description" ""
			(at 151.13 208.28 0)
			(effects
				(font
					(size 1.27 1.27)
				)
				(hide yes)
			)
		)
		(property "Author" "Antmicro"
			(at 142.24 215.9 0)
			(effects
				(font
					(size 1.27 1.27)
					(thickness 0.15)
				)
				(justify left bottom)
				(hide yes)
			)
		)
		(property "License" "Apache-2.0"
			(at 142.24 218.44 0)
			(effects
				(font
					(size 1.27 1.27)
					(thickness 0.15)
				)
				(justify left bottom)
				(hide yes)
			)
		)
		(pin "1"
		)
		(instances
			(project "cm4-baseboard"
				(path ""
					(reference "#PWR0502")
					(unit 1)
				)
			)
		)
	)
	(symbol
		(lib_id "antmicroCapacitors0402:C_1u_0402")
		(at 242.57 54.61 90)
		(unit 1)
		(exclude_from_sim no)
		(in_bom yes)
		(on_board yes)
		(dnp no)
		(property "Reference" "C504"
			(at 242.57 49.53 90)
			(effects
				(font
					(size 1.27 1.27)
				)
				(justify left)
			)
		)
		(property "Value" "C_1u_0402"
			(at 246.38 54.61 0)
			(effects
				(font
					(size 1.27 1.27)
				)
				(justify left bottom)
				(hide yes)
			)
		)
		(property "Footprint" "antmicro-footprints:C_0402_1005Metric"
			(at 237.49 49.53 0)
			(effects
				(font
					(size 1.524 1.524)
				)
				(justify left bottom)
				(hide yes)
			)
		)
		(property "Datasheet" "https://product.tdk.com/en/search/capacitor/ceramic/mlcc/info?part_no=C1005X6S1A105K050BC"
			(at 242.57 54.61 0)
			(effects
				(font
					(size 1.27 1.27)
				)
				(justify left bottom)
				(hide yes)
			)
		)
		(property "Description" ""
			(at 242.57 54.61 0)
			(effects
				(font
					(size 1.27 1.27)
				)
				(hide yes)
			)
		)
		(property "Manufacturer" "TDK"
			(at 232.41 49.53 0)
			(effects
				(font
					(size 1.524 1.524)
				)
				(justify left bottom)
				(hide yes)
			)
		)
		(property "MPN" "C1005X6S1A105K050BC"
			(at 234.95 49.53 0)
			(effects
				(font
					(size 1.524 1.524)
				)
				(justify left bottom)
				(hide yes)
			)
		)
		(property "Val" "1u"
			(at 241.3 54.61 90)
			(effects
				(font
					(size 1.27 1.27)
				)
				(justify left)
			)
		)
		(property "License" "Apache-2.0"
			(at 265.43 34.29 0)
			(effects
				(font
					(size 1.27 1.27)
					(thickness 0.15)
				)
				(justify left bottom)
				(hide yes)
			)
		)
		(property "Author" "Antmicro"
			(at 267.97 34.29 0)
			(effects
				(font
					(size 1.27 1.27)
					(thickness 0.15)
				)
				(justify left bottom)
				(hide yes)
			)
		)
		(property "Voltage" ""
			(at 270.51 34.29 0)
			(effects
				(font
					(size 1.27 1.27)
				)
				(justify left bottom)
				(hide yes)
			)
		)
		(property "Dielectric" ""
			(at 273.05 34.29 0)
			(effects
				(font
					(size 1.27 1.27)
				)
				(justify left bottom)
				(hide yes)
			)
		)
		(pin "1"
		)
		(pin "2"
		)
		(instances
			(project "cm4-baseboard"
				(path ""
					(reference "C504")
					(unit 1)
				)
			)
		)
	)
	(symbol
		(lib_id "antmicropower:GND")
		(at 204.47 125.73 0)
		(mirror y)
		(unit 1)
		(exclude_from_sim no)
		(in_bom yes)
		(on_board yes)
		(dnp no)
		(fields_autoplaced yes)
		(property "Reference" "#PWR0505"
			(at 195.58 128.27 0)
			(effects
				(font
					(size 1.27 1.27)
					(thickness 0.15)
				)
				(justify left bottom)
				(hide yes)
			)
		)
		(property "Value" "GND"
			(at 206.4802 130.81 0)
			(effects
				(font
					(size 1.27 1.27)
					(thickness 0.15)
				)
				(justify left bottom)
			)
		)
		(property "Footprint" ""
			(at 195.58 133.35 0)
			(effects
				(font
					(size 1.27 1.27)
					(thickness 0.15)
				)
				(justify left bottom)
				(hide yes)
			)
		)
		(property "Datasheet" ""
			(at 195.58 138.43 0)
			(effects
				(font
					(size 1.27 1.27)
					(thickness 0.15)
				)
				(justify left bottom)
				(hide yes)
			)
		)
		(property "Description" ""
			(at 204.47 125.73 0)
			(effects
				(font
					(size 1.27 1.27)
				)
				(hide yes)
			)
		)
		(property "Author" "Antmicro"
			(at 195.58 133.35 0)
			(effects
				(font
					(size 1.27 1.27)
					(thickness 0.15)
				)
				(justify left bottom)
				(hide yes)
			)
		)
		(property "License" "Apache-2.0"
			(at 195.58 135.89 0)
			(effects
				(font
					(size 1.27 1.27)
					(thickness 0.15)
				)
				(justify left bottom)
				(hide yes)
			)
		)
		(pin "1"
		)
		(instances
			(project "cm4-baseboard"
				(path ""
					(reference "#PWR0505")
					(unit 1)
				)
			)
		)
	)
	(symbol
		(lib_id "antmicroResistors0402:R_10k_0402")
		(at 187.96 191.77 270)
		(unit 1)
		(exclude_from_sim no)
		(in_bom yes)
		(on_board yes)
		(dnp no)
		(property "Reference" "R504"
			(at 194.31 193.04 90)
			(effects
				(font
					(size 1.27 1.27)
					(thickness 0.15)
				)
				(justify right)
			)
		)
		(property "Value" "R_10k_0402"
			(at 175.26 212.09 0)
			(effects
				(font
					(size 1.27 1.27)
					(thickness 0.15)
				)
				(justify left bottom)
				(hide yes)
			)
		)
		(property "Footprint" "antmicro-footprints:R_0402_1005Metric"
			(at 172.72 212.09 0)
			(effects
				(font
					(size 1.27 1.27)
					(thickness 0.15)
				)
				(justify left bottom)
				(hide yes)
			)
		)
		(property "Datasheet" "https://www.bourns.com/docs/product-datasheets/cr.pdf"
			(at 170.18 212.09 0)
			(effects
				(font
					(size 1.27 1.27)
					(thickness 0.15)
				)
				(justify left bottom)
				(hide yes)
			)
		)
		(property "Description" ""
			(at 187.96 191.77 0)
			(effects
				(font
					(size 1.27 1.27)
				)
				(hide yes)
			)
		)
		(property "Manufacturer" "Bourns"
			(at 165.1 212.09 0)
			(effects
				(font
					(size 1.27 1.27)
					(thickness 0.15)
				)
				(justify left bottom)
				(hide yes)
			)
		)
		(property "MPN" "CR0402-FX-1002GLF"
			(at 167.64 212.09 0)
			(effects
				(font
					(size 1.27 1.27)
					(thickness 0.15)
				)
				(justify left bottom)
				(hide yes)
			)
		)
		(property "Val" "10k"
			(at 193.04 195.58 90)
			(effects
				(font
					(size 1.27 1.27)
					(thickness 0.15)
				)
				(justify right)
			)
		)
		(property "License" "Apache-2.0"
			(at 162.56 212.09 0)
			(effects
				(font
					(size 1.27 1.27)
					(thickness 0.15)
				)
				(justify left bottom)
				(hide yes)
			)
		)
		(property "Author" "Antmicro"
			(at 160.02 212.09 0)
			(effects
				(font
					(size 1.27 1.27)
					(thickness 0.15)
				)
				(justify left bottom)
				(hide yes)
			)
		)
		(property "Tolerance" "1%"
			(at 177.8 212.09 0)
			(effects
				(font
					(size 1.27 1.27)
				)
				(justify left bottom)
				(hide yes)
			)
		)
		(pin "1"
		)
		(pin "2"
		)
		(instances
			(project "cm4-baseboard"
				(path ""
					(reference "R504")
					(unit 1)
				)
			)
		)
	)
	(symbol
		(lib_id "antmicroTestPoints:TP_0.75mm_SMD")
		(at 204.47 76.2 0)
		(mirror x)
		(unit 1)
		(exclude_from_sim no)
		(in_bom no)
		(on_board yes)
		(dnp no)
		(property "Reference" "TP503"
			(at 212.09 76.2 0)
			(effects
				(font
					(size 1.27 1.27)
				)
			)
		)
		(property "Value" "TP_0.75mm_SMD"
			(at 204.47 73.66 0)
			(effects
				(font
					(size 1.27 1.27)
				)
				(justify left bottom)
				(hide yes)
			)
		)
		(property "Footprint" "antmicro-footprints:TP_SMD_0.75mm"
			(at 209.55 81.28 0)
			(effects
				(font
					(size 1.524 1.524)
				)
				(justify left bottom)
				(hide yes)
			)
		)
		(property "Datasheet" ""
			(at 209.55 83.82 0)
			(effects
				(font
					(size 1.524 1.524)
				)
				(justify left bottom)
				(hide yes)
			)
		)
		(property "Description" ""
			(at 204.47 76.2 0)
			(effects
				(font
					(size 1.27 1.27)
				)
				(hide yes)
			)
		)
		(property "MPN" ""
			(at 204.47 76.2 0)
			(effects
				(font
					(size 1.27 1.27)
				)
				(hide yes)
			)
		)
		(property "Manufacturer" ""
			(at 204.47 76.2 0)
			(effects
				(font
					(size 1.27 1.27)
				)
				(hide yes)
			)
		)
		(property "Author" "Antmicro"
			(at 219.71 60.96 0)
			(effects
				(font
					(size 1.27 1.27)
					(thickness 0.15)
				)
				(justify left bottom)
				(hide yes)
			)
		)
		(property "License" "Apache-2.0"
			(at 219.71 58.42 0)
			(effects
				(font
					(size 1.27 1.27)
					(thickness 0.15)
				)
				(justify left bottom)
				(hide yes)
			)
		)
		(pin "1"
		)
		(instances
			(project "cm4-baseboard"
				(path ""
					(reference "TP503")
					(unit 1)
				)
			)
		)
	)
	(symbol
		(lib_id "antmicroLEDIndicationDiscrete:LED_G_0603_KP-1608CGCK")
		(at 205.74 100.33 270)
		(mirror x)
		(unit 1)
		(exclude_from_sim no)
		(in_bom yes)
		(on_board yes)
		(dnp no)
		(property "Reference" "D503"
			(at 212.09 96.52 90)
			(effects
				(font
					(size 1.27 1.27)
					(thickness 0.15)
				)
			)
		)
		(property "Value" "LED_G_0603_KP-1608CGCK"
			(at 198.12 77.47 0)
			(effects
				(font
					(size 1.27 1.27)
					(thickness 0.15)
				)
				(justify left bottom)
				(hide yes)
			)
		)
		(property "Footprint" "antmicro-footprints:LED_0603_1608Metric_G"
			(at 195.58 77.47 0)
			(effects
				(font
					(size 1.27 1.27)
					(thickness 0.15)
				)
				(justify left bottom)
				(hide yes)
			)
		)
		(property "Datasheet" "http://www.kingbright.com/attachments/file/psearch//000/00/00/KP-1608CGCK(Ver.23B).pdf"
			(at 193.04 77.47 0)
			(effects
				(font
					(size 1.27 1.27)
					(thickness 0.15)
				)
				(justify left bottom)
				(hide yes)
			)
		)
		(property "Description" ""
			(at 205.74 100.33 0)
			(effects
				(font
					(size 1.27 1.27)
				)
				(hide yes)
			)
		)
		(property "MPN" "KP-1608CGCK"
			(at 190.5 77.47 0)
			(effects
				(font
					(size 1.27 1.27)
					(thickness 0.15)
				)
				(justify left bottom)
				(hide yes)
			)
		)
		(property "Manufacturer" "Kingbright"
			(at 187.96 77.47 0)
			(effects
				(font
					(size 1.27 1.27)
					(thickness 0.15)
				)
				(justify left bottom)
				(hide yes)
			)
		)
		(property "Color" "Green"
			(at 212.09 99.06 90)
			(effects
				(font
					(size 1.27 1.27)
				)
			)
		)
		(property "Author" "Antmicro"
			(at 185.42 77.47 0)
			(effects
				(font
					(size 1.27 1.27)
					(thickness 0.15)
				)
				(justify left bottom)
				(hide yes)
			)
		)
		(property "License" "Apache-2.0"
			(at 182.88 77.47 0)
			(effects
				(font
					(size 1.27 1.27)
					(thickness 0.15)
				)
				(justify left bottom)
				(hide yes)
			)
		)
		(pin "2"
		)
		(pin "1"
		)
		(instances
			(project "cm4-baseboard"
				(path ""
					(reference "D503")
					(unit 1)
				)
			)
		)
	)
	(symbol
		(lib_id "antmicroMechanicalParts:Spacer_Drill3.7mm_H2.5mm_9774025151R")
		(at 265.43 119.38 180)
		(unit 1)
		(exclude_from_sim no)
		(in_bom yes)
		(on_board yes)
		(dnp no)
		(fields_autoplaced yes)
		(property "Reference" "H501"
			(at 260.35 111.76 0)
			(effects
				(font
					(size 1.27 1.27)
					(thickness 0.15)
				)
			)
		)
		(property "Value" "Spacer_Drill3.7mm_H2.5mm_9774025151R"
			(at 260.35 114.3 0)
			(effects
				(font
					(size 1.27 1.27)
					(thickness 0.15)
				)
			)
		)
		(property "Footprint" "antmicro-footprints:Spacer_Drill3.7mm_H2.5mm_9774025151R"
			(at 242.57 111.76 0)
			(effects
				(font
					(size 1.27 1.27)
					(thickness 0.15)
				)
				(justify left bottom)
				(hide yes)
			)
		)
		(property "Datasheet" "https://www.we-online.com/components/products/datasheet/9774025151R.pdf"
			(at 242.57 109.22 0)
			(effects
				(font
					(size 1.27 1.27)
					(thickness 0.15)
				)
				(justify left bottom)
				(hide yes)
			)
		)
		(property "Description" ""
			(at 265.43 119.38 0)
			(effects
				(font
					(size 1.27 1.27)
				)
				(hide yes)
			)
		)
		(property "Manufacturer" "Würth Elektronik"
			(at 242.57 106.68 0)
			(effects
				(font
					(size 1.27 1.27)
					(thickness 0.15)
				)
				(justify left bottom)
				(hide yes)
			)
		)
		(property "MPN" "9774025151R"
			(at 242.57 104.14 0)
			(effects
				(font
					(size 1.27 1.27)
					(thickness 0.15)
				)
				(justify left bottom)
				(hide yes)
			)
		)
		(property "Author" "Antmicro"
			(at 242.57 101.6 0)
			(effects
				(font
					(size 1.27 1.27)
					(thickness 0.15)
				)
				(justify left bottom)
				(hide yes)
			)
		)
		(property "License" "Apache-2.0"
			(at 242.57 99.06 0)
			(effects
				(font
					(size 1.27 1.27)
					(thickness 0.15)
				)
				(justify left bottom)
				(hide yes)
			)
		)
		(pin "1"
		)
		(instances
			(project "cm4-baseboard"
				(path ""
					(reference "H501")
					(unit 1)
				)
			)
		)
	)
	(symbol
		(lib_id "antmicroTestPoints:TP_0.75mm_SMD")
		(at 204.47 73.66 0)
		(mirror x)
		(unit 1)
		(exclude_from_sim no)
		(in_bom no)
		(on_board yes)
		(dnp no)
		(property "Reference" "TP502"
			(at 212.09 73.66 0)
			(effects
				(font
					(size 1.27 1.27)
				)
			)
		)
		(property "Value" "TP_0.75mm_SMD"
			(at 204.47 71.12 0)
			(effects
				(font
					(size 1.27 1.27)
				)
				(justify left bottom)
				(hide yes)
			)
		)
		(property "Footprint" "antmicro-footprints:TP_SMD_0.75mm"
			(at 209.55 78.74 0)
			(effects
				(font
					(size 1.524 1.524)
				)
				(justify left bottom)
				(hide yes)
			)
		)
		(property "Datasheet" ""
			(at 209.55 81.28 0)
			(effects
				(font
					(size 1.524 1.524)
				)
				(justify left bottom)
				(hide yes)
			)
		)
		(property "Description" ""
			(at 204.47 73.66 0)
			(effects
				(font
					(size 1.27 1.27)
				)
				(hide yes)
			)
		)
		(property "MPN" ""
			(at 204.47 73.66 0)
			(effects
				(font
					(size 1.27 1.27)
				)
				(hide yes)
			)
		)
		(property "Manufacturer" ""
			(at 204.47 73.66 0)
			(effects
				(font
					(size 1.27 1.27)
				)
				(hide yes)
			)
		)
		(property "Author" "Antmicro"
			(at 219.71 58.42 0)
			(effects
				(font
					(size 1.27 1.27)
					(thickness 0.15)
				)
				(justify left bottom)
				(hide yes)
			)
		)
		(property "License" "Apache-2.0"
			(at 219.71 55.88 0)
			(effects
				(font
					(size 1.27 1.27)
					(thickness 0.15)
				)
				(justify left bottom)
				(hide yes)
			)
		)
		(pin "1"
		)
		(instances
			(project "cm4-baseboard"
				(path ""
					(reference "TP502")
					(unit 1)
				)
			)
		)
	)
	(symbol
		(lib_id "antmicroResistors0402:R_10k_0402")
		(at 210.82 191.77 270)
		(unit 1)
		(exclude_from_sim no)
		(in_bom yes)
		(on_board yes)
		(dnp no)
		(property "Reference" "R508"
			(at 212.09 193.04 90)
			(effects
				(font
					(size 1.27 1.27)
					(thickness 0.15)
				)
				(justify left)
			)
		)
		(property "Value" "R_10k_0402"
			(at 198.12 212.09 0)
			(effects
				(font
					(size 1.27 1.27)
					(thickness 0.15)
				)
				(justify left bottom)
				(hide yes)
			)
		)
		(property "Footprint" "antmicro-footprints:R_0402_1005Metric"
			(at 195.58 212.09 0)
			(effects
				(font
					(size 1.27 1.27)
					(thickness 0.15)
				)
				(justify left bottom)
				(hide yes)
			)
		)
		(property "Datasheet" "https://www.bourns.com/docs/product-datasheets/cr.pdf"
			(at 193.04 212.09 0)
			(effects
				(font
					(size 1.27 1.27)
					(thickness 0.15)
				)
				(justify left bottom)
				(hide yes)
			)
		)
		(property "Description" ""
			(at 210.82 191.77 0)
			(effects
				(font
					(size 1.27 1.27)
				)
				(hide yes)
			)
		)
		(property "Manufacturer" "Bourns"
			(at 187.96 212.09 0)
			(effects
				(font
					(size 1.27 1.27)
					(thickness 0.15)
				)
				(justify left bottom)
				(hide yes)
			)
		)
		(property "MPN" "CR0402-FX-1002GLF"
			(at 190.5 212.09 0)
			(effects
				(font
					(size 1.27 1.27)
					(thickness 0.15)
				)
				(justify left bottom)
				(hide yes)
			)
		)
		(property "Val" "10k"
			(at 212.09 195.58 90)
			(effects
				(font
					(size 1.27 1.27)
					(thickness 0.15)
				)
				(justify left)
			)
		)
		(property "License" "Apache-2.0"
			(at 185.42 212.09 0)
			(effects
				(font
					(size 1.27 1.27)
					(thickness 0.15)
				)
				(justify left bottom)
				(hide yes)
			)
		)
		(property "Author" "Antmicro"
			(at 182.88 212.09 0)
			(effects
				(font
					(size 1.27 1.27)
					(thickness 0.15)
				)
				(justify left bottom)
				(hide yes)
			)
		)
		(property "Tolerance" "1%"
			(at 200.66 212.09 0)
			(effects
				(font
					(size 1.27 1.27)
				)
				(justify left bottom)
				(hide yes)
			)
		)
		(pin "1"
		)
		(pin "2"
		)
		(instances
			(project "cm4-baseboard"
				(path ""
					(reference "R508")
					(unit 1)
				)
			)
		)
	)
	(symbol
		(lib_id "antmicropower:GND")
		(at 242.57 224.79 0)
		(unit 1)
		(exclude_from_sim no)
		(in_bom yes)
		(on_board yes)
		(dnp no)
		(fields_autoplaced yes)
		(property "Reference" "#PWR0509"
			(at 251.46 227.33 0)
			(effects
				(font
					(size 1.27 1.27)
					(thickness 0.15)
				)
				(justify left bottom)
				(hide yes)
			)
		)
		(property "Value" "GND"
			(at 240.5598 229.87 0)
			(effects
				(font
					(size 1.27 1.27)
					(thickness 0.15)
				)
				(justify left bottom)
			)
		)
		(property "Footprint" ""
			(at 251.46 232.41 0)
			(effects
				(font
					(size 1.27 1.27)
					(thickness 0.15)
				)
				(justify left bottom)
				(hide yes)
			)
		)
		(property "Datasheet" ""
			(at 251.46 237.49 0)
			(effects
				(font
					(size 1.27 1.27)
					(thickness 0.15)
				)
				(justify left bottom)
				(hide yes)
			)
		)
		(property "Description" ""
			(at 242.57 224.79 0)
			(effects
				(font
					(size 1.27 1.27)
				)
				(hide yes)
			)
		)
		(property "Author" "Antmicro"
			(at 251.46 232.41 0)
			(effects
				(font
					(size 1.27 1.27)
					(thickness 0.15)
				)
				(justify left bottom)
				(hide yes)
			)
		)
		(property "License" "Apache-2.0"
			(at 251.46 234.95 0)
			(effects
				(font
					(size 1.27 1.27)
					(thickness 0.15)
				)
				(justify left bottom)
				(hide yes)
			)
		)
		(pin "1"
		)
		(instances
			(project "cm4-baseboard"
				(path ""
					(reference "#PWR0509")
					(unit 1)
				)
			)
		)
	)
	(symbol
		(lib_id "antmicropower:GND")
		(at 234.95 231.14 0)
		(unit 1)
		(exclude_from_sim no)
		(in_bom yes)
		(on_board yes)
		(dnp no)
		(fields_autoplaced yes)
		(property "Reference" "#PWR0507"
			(at 243.84 233.68 0)
			(effects
				(font
					(size 1.27 1.27)
					(thickness 0.15)
				)
				(justify left bottom)
				(hide yes)
			)
		)
		(property "Value" "GND"
			(at 232.9398 236.22 0)
			(effects
				(font
					(size 1.27 1.27)
					(thickness 0.15)
				)
				(justify left bottom)
			)
		)
		(property "Footprint" ""
			(at 243.84 238.76 0)
			(effects
				(font
					(size 1.27 1.27)
					(thickness 0.15)
				)
				(justify left bottom)
				(hide yes)
			)
		)
		(property "Datasheet" ""
			(at 243.84 243.84 0)
			(effects
				(font
					(size 1.27 1.27)
					(thickness 0.15)
				)
				(justify left bottom)
				(hide yes)
			)
		)
		(property "Description" ""
			(at 234.95 231.14 0)
			(effects
				(font
					(size 1.27 1.27)
				)
				(hide yes)
			)
		)
		(property "Author" "Antmicro"
			(at 243.84 238.76 0)
			(effects
				(font
					(size 1.27 1.27)
					(thickness 0.15)
				)
				(justify left bottom)
				(hide yes)
			)
		)
		(property "License" "Apache-2.0"
			(at 243.84 241.3 0)
			(effects
				(font
					(size 1.27 1.27)
					(thickness 0.15)
				)
				(justify left bottom)
				(hide yes)
			)
		)
		(pin "1"
		)
		(instances
			(project "cm4-baseboard"
				(path ""
					(reference "#PWR0507")
					(unit 1)
				)
			)
		)
	)
	(symbol
		(lib_id "antmicroResistors0402:R_10k_0402")
		(at 234.95 224.79 90)
		(mirror x)
		(unit 1)
		(exclude_from_sim no)
		(in_bom yes)
		(on_board yes)
		(dnp no)
		(property "Reference" "R513"
			(at 233.68 226.06 90)
			(effects
				(font
					(size 1.27 1.27)
					(thickness 0.15)
				)
				(justify left)
			)
		)
		(property "Value" "R_10k_0402"
			(at 247.65 245.11 0)
			(effects
				(font
					(size 1.27 1.27)
					(thickness 0.15)
				)
				(justify left bottom)
				(hide yes)
			)
		)
		(property "Footprint" "antmicro-footprints:R_0402_1005Metric"
			(at 250.19 245.11 0)
			(effects
				(font
					(size 1.27 1.27)
					(thickness 0.15)
				)
				(justify left bottom)
				(hide yes)
			)
		)
		(property "Datasheet" "https://www.bourns.com/docs/product-datasheets/cr.pdf"
			(at 252.73 245.11 0)
			(effects
				(font
					(size 1.27 1.27)
					(thickness 0.15)
				)
				(justify left bottom)
				(hide yes)
			)
		)
		(property "Description" ""
			(at 234.95 224.79 0)
			(effects
				(font
					(size 1.27 1.27)
				)
				(hide yes)
			)
		)
		(property "Manufacturer" "Bourns"
			(at 257.81 245.11 0)
			(effects
				(font
					(size 1.27 1.27)
					(thickness 0.15)
				)
				(justify left bottom)
				(hide yes)
			)
		)
		(property "MPN" "CR0402-FX-1002GLF"
			(at 255.27 245.11 0)
			(effects
				(font
					(size 1.27 1.27)
					(thickness 0.15)
				)
				(justify left bottom)
				(hide yes)
			)
		)
		(property "Val" "10k"
			(at 233.68 228.6 90)
			(effects
				(font
					(size 1.27 1.27)
					(thickness 0.15)
				)
				(justify left)
			)
		)
		(property "License" "Apache-2.0"
			(at 260.35 245.11 0)
			(effects
				(font
					(size 1.27 1.27)
					(thickness 0.15)
				)
				(justify left bottom)
				(hide yes)
			)
		)
		(property "Author" "Antmicro"
			(at 262.89 245.11 0)
			(effects
				(font
					(size 1.27 1.27)
					(thickness 0.15)
				)
				(justify left bottom)
				(hide yes)
			)
		)
		(property "Tolerance" "1%"
			(at 245.11 245.11 0)
			(effects
				(font
					(size 1.27 1.27)
				)
				(justify left bottom)
				(hide yes)
			)
		)
		(pin "1"
		)
		(pin "2"
		)
		(instances
			(project "cm4-baseboard"
				(path ""
					(reference "R513")
					(unit 1)
				)
			)
		)
	)
	(symbol
		(lib_id "antmicropower:GND")
		(at 285.75 199.39 0)
		(mirror y)
		(unit 1)
		(exclude_from_sim no)
		(in_bom yes)
		(on_board yes)
		(dnp no)
		(fields_autoplaced yes)
		(property "Reference" "#PWR0516"
			(at 285.75 205.74 0)
			(effects
				(font
					(size 1.27 1.27)
				)
				(justify left bottom)
				(hide yes)
			)
		)
		(property "Value" "GND"
			(at 285.75 204.47 0)
			(effects
				(font
					(size 1.27 1.27)
				)
			)
		)
		(property "Footprint" ""
			(at 285.75 199.39 0)
			(effects
				(font
					(size 1.27 1.27)
				)
				(hide yes)
			)
		)
		(property "Datasheet" ""
			(at 285.75 199.39 0)
			(effects
				(font
					(size 1.27 1.27)
				)
				(hide yes)
			)
		)
		(property "Description" ""
			(at 285.75 199.39 0)
			(effects
				(font
					(size 1.27 1.27)
				)
				(hide yes)
			)
		)
		(property "Author" "Antmicro"
			(at 276.86 207.01 0)
			(effects
				(font
					(size 1.27 1.27)
					(thickness 0.15)
				)
				(justify left bottom)
				(hide yes)
			)
		)
		(property "License" "Apache-2.0"
			(at 276.86 209.55 0)
			(effects
				(font
					(size 1.27 1.27)
					(thickness 0.15)
				)
				(justify left bottom)
				(hide yes)
			)
		)
		(pin "1"
		)
		(instances
			(project "cm4-baseboard"
				(path ""
					(reference "#PWR0516")
					(unit 1)
				)
			)
		)
	)
	(symbol
		(lib_id "antmicroResistors0402:R_10k_0402")
		(at 226.06 191.77 270)
		(unit 1)
		(exclude_from_sim no)
		(in_bom yes)
		(on_board yes)
		(dnp no)
		(property "Reference" "R511"
			(at 227.33 193.04 90)
			(effects
				(font
					(size 1.27 1.27)
					(thickness 0.15)
				)
				(justify left)
			)
		)
		(property "Value" "R_10k_0402"
			(at 213.36 212.09 0)
			(effects
				(font
					(size 1.27 1.27)
					(thickness 0.15)
				)
				(justify left bottom)
				(hide yes)
			)
		)
		(property "Footprint" "antmicro-footprints:R_0402_1005Metric"
			(at 210.82 212.09 0)
			(effects
				(font
					(size 1.27 1.27)
					(thickness 0.15)
				)
				(justify left bottom)
				(hide yes)
			)
		)
		(property "Datasheet" "https://www.bourns.com/docs/product-datasheets/cr.pdf"
			(at 208.28 212.09 0)
			(effects
				(font
					(size 1.27 1.27)
					(thickness 0.15)
				)
				(justify left bottom)
				(hide yes)
			)
		)
		(property "Description" ""
			(at 226.06 191.77 0)
			(effects
				(font
					(size 1.27 1.27)
				)
				(hide yes)
			)
		)
		(property "Manufacturer" "Bourns"
			(at 203.2 212.09 0)
			(effects
				(font
					(size 1.27 1.27)
					(thickness 0.15)
				)
				(justify left bottom)
				(hide yes)
			)
		)
		(property "MPN" "CR0402-FX-1002GLF"
			(at 205.74 212.09 0)
			(effects
				(font
					(size 1.27 1.27)
					(thickness 0.15)
				)
				(justify left bottom)
				(hide yes)
			)
		)
		(property "Val" "10k"
			(at 227.33 195.58 90)
			(effects
				(font
					(size 1.27 1.27)
					(thickness 0.15)
				)
				(justify left)
			)
		)
		(property "License" "Apache-2.0"
			(at 200.66 212.09 0)
			(effects
				(font
					(size 1.27 1.27)
					(thickness 0.15)
				)
				(justify left bottom)
				(hide yes)
			)
		)
		(property "Author" "Antmicro"
			(at 198.12 212.09 0)
			(effects
				(font
					(size 1.27 1.27)
					(thickness 0.15)
				)
				(justify left bottom)
				(hide yes)
			)
		)
		(property "Tolerance" "1%"
			(at 215.9 212.09 0)
			(effects
				(font
					(size 1.27 1.27)
				)
				(justify left bottom)
				(hide yes)
			)
		)
		(pin "1"
		)
		(pin "2"
		)
		(instances
			(project "cm4-baseboard"
				(path ""
					(reference "R511")
					(unit 1)
				)
			)
		)
	)
	(symbol
		(lib_id "antmicroTestPoints:TP_0.75mm_SMD")
		(at 204.47 78.74 0)
		(mirror x)
		(unit 1)
		(exclude_from_sim no)
		(in_bom no)
		(on_board yes)
		(dnp no)
		(property "Reference" "TP504"
			(at 212.09 78.74 0)
			(effects
				(font
					(size 1.27 1.27)
				)
			)
		)
		(property "Value" "TP_0.75mm_SMD"
			(at 204.47 76.2 0)
			(effects
				(font
					(size 1.27 1.27)
				)
				(justify left bottom)
				(hide yes)
			)
		)
		(property "Footprint" "antmicro-footprints:TP_SMD_0.75mm"
			(at 209.55 83.82 0)
			(effects
				(font
					(size 1.524 1.524)
				)
				(justify left bottom)
				(hide yes)
			)
		)
		(property "Datasheet" ""
			(at 209.55 86.36 0)
			(effects
				(font
					(size 1.524 1.524)
				)
				(justify left bottom)
				(hide yes)
			)
		)
		(property "Description" ""
			(at 204.47 78.74 0)
			(effects
				(font
					(size 1.27 1.27)
				)
				(hide yes)
			)
		)
		(property "MPN" ""
			(at 204.47 78.74 0)
			(effects
				(font
					(size 1.27 1.27)
				)
				(hide yes)
			)
		)
		(property "Manufacturer" ""
			(at 204.47 78.74 0)
			(effects
				(font
					(size 1.27 1.27)
				)
				(hide yes)
			)
		)
		(property "Author" "Antmicro"
			(at 219.71 63.5 0)
			(effects
				(font
					(size 1.27 1.27)
					(thickness 0.15)
				)
				(justify left bottom)
				(hide yes)
			)
		)
		(property "License" "Apache-2.0"
			(at 219.71 60.96 0)
			(effects
				(font
					(size 1.27 1.27)
					(thickness 0.15)
				)
				(justify left bottom)
				(hide yes)
			)
		)
		(pin "1"
		)
		(instances
			(project "cm4-baseboard"
				(path ""
					(reference "TP504")
					(unit 1)
				)
			)
		)
	)
	(symbol
		(lib_id "antmicroResistors0402:R_10k_0402")
		(at 170.18 41.91 90)
		(unit 1)
		(exclude_from_sim no)
		(in_bom yes)
		(on_board yes)
		(dnp no)
		(property "Reference" "R503"
			(at 168.91 38.1 90)
			(effects
				(font
					(size 1.27 1.27)
				)
				(justify left)
			)
		)
		(property "Value" "R_10k_0402"
			(at 173.99 41.91 0)
			(effects
				(font
					(size 1.27 1.27)
				)
				(justify left bottom)
				(hide yes)
			)
		)
		(property "Footprint" "antmicro-footprints:R_0402_1005Metric"
			(at 165.1 36.83 0)
			(effects
				(font
					(size 1.524 1.524)
				)
				(justify left bottom)
				(hide yes)
			)
		)
		(property "Datasheet" "https://www.bourns.com/docs/product-datasheets/cr.pdf"
			(at 170.18 41.91 0)
			(effects
				(font
					(size 1.27 1.27)
				)
				(justify left bottom)
				(hide yes)
			)
		)
		(property "Description" ""
			(at 170.18 41.91 0)
			(effects
				(font
					(size 1.27 1.27)
				)
				(hide yes)
			)
		)
		(property "Manufacturer" "Bourns"
			(at 160.02 36.83 0)
			(effects
				(font
					(size 1.524 1.524)
				)
				(justify left bottom)
				(hide yes)
			)
		)
		(property "MPN" "CR0402-FX-1002GLF"
			(at 162.56 36.83 0)
			(effects
				(font
					(size 1.524 1.524)
				)
				(justify left bottom)
				(hide yes)
			)
		)
		(property "Val" "10k"
			(at 168.91 40.64 90)
			(effects
				(font
					(size 1.27 1.27)
				)
				(justify left)
			)
		)
		(property "License" "Apache-2.0"
			(at 195.58 21.59 0)
			(effects
				(font
					(size 1.27 1.27)
					(thickness 0.15)
				)
				(justify left bottom)
				(hide yes)
			)
		)
		(property "Author" "Antmicro"
			(at 198.12 21.59 0)
			(effects
				(font
					(size 1.27 1.27)
					(thickness 0.15)
				)
				(justify left bottom)
				(hide yes)
			)
		)
		(property "Tolerance" "1%"
			(at 180.34 21.59 0)
			(effects
				(font
					(size 1.27 1.27)
				)
				(justify left bottom)
				(hide yes)
			)
		)
		(pin "1"
		)
		(pin "2"
		)
		(instances
			(project "cm4-baseboard"
				(path ""
					(reference "R503")
					(unit 1)
				)
			)
		)
	)
	(symbol
		(lib_id "antmicroTestPoints:TP_0.75mm_SMD")
		(at 204.47 59.69 0)
		(mirror x)
		(unit 1)
		(exclude_from_sim no)
		(in_bom no)
		(on_board yes)
		(dnp no)
		(property "Reference" "TP501"
			(at 207.01 57.15 0)
			(effects
				(font
					(size 1.27 1.27)
				)
			)
		)
		(property "Value" "TP_0.75mm_SMD"
			(at 204.47 57.15 0)
			(effects
				(font
					(size 1.27 1.27)
				)
				(justify left bottom)
				(hide yes)
			)
		)
		(property "Footprint" "antmicro-footprints:TP_SMD_0.75mm"
			(at 209.55 64.77 0)
			(effects
				(font
					(size 1.524 1.524)
				)
				(justify left bottom)
				(hide yes)
			)
		)
		(property "Datasheet" ""
			(at 209.55 67.31 0)
			(effects
				(font
					(size 1.524 1.524)
				)
				(justify left bottom)
				(hide yes)
			)
		)
		(property "Description" ""
			(at 204.47 59.69 0)
			(effects
				(font
					(size 1.27 1.27)
				)
				(hide yes)
			)
		)
		(property "MPN" ""
			(at 204.47 59.69 0)
			(effects
				(font
					(size 1.27 1.27)
				)
				(hide yes)
			)
		)
		(property "Manufacturer" ""
			(at 204.47 59.69 0)
			(effects
				(font
					(size 1.27 1.27)
				)
				(hide yes)
			)
		)
		(property "Author" "Antmicro"
			(at 219.71 44.45 0)
			(effects
				(font
					(size 1.27 1.27)
					(thickness 0.15)
				)
				(justify left bottom)
				(hide yes)
			)
		)
		(property "License" "Apache-2.0"
			(at 219.71 41.91 0)
			(effects
				(font
					(size 1.27 1.27)
					(thickness 0.15)
				)
				(justify left bottom)
				(hide yes)
			)
		)
		(pin "1"
		)
		(instances
			(project "cm4-baseboard"
				(path ""
					(reference "TP501")
					(unit 1)
				)
			)
		)
	)
	(symbol
		(lib_id "antmicroCapacitors0402:C_10u_0402")
		(at 217.17 54.61 90)
		(unit 1)
		(exclude_from_sim no)
		(in_bom yes)
		(on_board yes)
		(dnp no)
		(property "Reference" "C501"
			(at 217.17 49.53 90)
			(effects
				(font
					(size 1.27 1.27)
					(thickness 0.15)
				)
				(justify left)
			)
		)
		(property "Value" "C_10u_0402"
			(at 227.33 34.29 0)
			(effects
				(font
					(size 1.27 1.27)
					(thickness 0.15)
				)
				(justify left bottom)
				(hide yes)
			)
		)
		(property "Footprint" "antmicro-footprints:C_0402_1005Metric"
			(at 229.87 34.29 0)
			(effects
				(font
					(size 1.27 1.27)
					(thickness 0.15)
				)
				(justify left bottom)
				(hide yes)
			)
		)
		(property "Datasheet" "https://www.yageo.com/en/Chart/Download/pdf/CC0402MRX5R5BB106"
			(at 232.41 34.29 0)
			(effects
				(font
					(size 1.27 1.27)
					(thickness 0.15)
				)
				(justify left bottom)
				(hide yes)
			)
		)
		(property "Description" ""
			(at 217.17 54.61 0)
			(effects
				(font
					(size 1.27 1.27)
				)
				(hide yes)
			)
		)
		(property "MPN" "CC0402MRX5R5BB106"
			(at 234.95 34.29 0)
			(effects
				(font
					(size 1.27 1.27)
					(thickness 0.15)
				)
				(justify left bottom)
				(hide yes)
			)
		)
		(property "Manufacturer" "YAGEO"
			(at 237.49 34.29 0)
			(effects
				(font
					(size 1.27 1.27)
					(thickness 0.15)
				)
				(justify left bottom)
				(hide yes)
			)
		)
		(property "License" "Apache-2.0"
			(at 240.03 34.29 0)
			(effects
				(font
					(size 1.27 1.27)
					(thickness 0.15)
				)
				(justify left bottom)
				(hide yes)
			)
		)
		(property "Author" "Antmicro"
			(at 242.57 34.29 0)
			(effects
				(font
					(size 1.27 1.27)
					(thickness 0.15)
				)
				(justify left bottom)
				(hide yes)
			)
		)
		(property "Val" "10u"
			(at 217.17 54.61 90)
			(effects
				(font
					(size 1.27 1.27)
					(thickness 0.15)
				)
				(justify left)
			)
		)
		(property "Voltage" ""
			(at 245.11 34.29 0)
			(effects
				(font
					(size 1.27 1.27)
				)
				(justify left bottom)
				(hide yes)
			)
		)
		(property "Dielectric" ""
			(at 247.65 34.29 0)
			(effects
				(font
					(size 1.27 1.27)
				)
				(justify left bottom)
				(hide yes)
			)
		)
		(pin "1"
		)
		(pin "2"
		)
		(instances
			(project "cm4-baseboard"
				(path ""
					(reference "C501")
					(unit 1)
				)
			)
		)
	)
	(symbol
		(lib_id "antmicroResistors0402:R_10k_0402")
		(at 154.94 41.91 90)
		(unit 1)
		(exclude_from_sim no)
		(in_bom yes)
		(on_board yes)
		(dnp no)
		(property "Reference" "R501"
			(at 153.67 38.1 90)
			(effects
				(font
					(size 1.27 1.27)
				)
				(justify left)
			)
		)
		(property "Value" "R_10k_0402"
			(at 158.75 41.91 0)
			(effects
				(font
					(size 1.27 1.27)
				)
				(justify left bottom)
				(hide yes)
			)
		)
		(property "Footprint" "antmicro-footprints:R_0402_1005Metric"
			(at 149.86 36.83 0)
			(effects
				(font
					(size 1.524 1.524)
				)
				(justify left bottom)
				(hide yes)
			)
		)
		(property "Datasheet" "https://www.bourns.com/docs/product-datasheets/cr.pdf"
			(at 154.94 41.91 0)
			(effects
				(font
					(size 1.27 1.27)
				)
				(justify left bottom)
				(hide yes)
			)
		)
		(property "Description" ""
			(at 154.94 41.91 0)
			(effects
				(font
					(size 1.27 1.27)
				)
				(hide yes)
			)
		)
		(property "Manufacturer" "Bourns"
			(at 144.78 36.83 0)
			(effects
				(font
					(size 1.524 1.524)
				)
				(justify left bottom)
				(hide yes)
			)
		)
		(property "MPN" "CR0402-FX-1002GLF"
			(at 147.32 36.83 0)
			(effects
				(font
					(size 1.524 1.524)
				)
				(justify left bottom)
				(hide yes)
			)
		)
		(property "Val" "10k"
			(at 153.67 40.64 90)
			(effects
				(font
					(size 1.27 1.27)
				)
				(justify left)
			)
		)
		(property "License" "Apache-2.0"
			(at 180.34 21.59 0)
			(effects
				(font
					(size 1.27 1.27)
					(thickness 0.15)
				)
				(justify left bottom)
				(hide yes)
			)
		)
		(property "Author" "Antmicro"
			(at 182.88 21.59 0)
			(effects
				(font
					(size 1.27 1.27)
					(thickness 0.15)
				)
				(justify left bottom)
				(hide yes)
			)
		)
		(property "Tolerance" "1%"
			(at 165.1 21.59 0)
			(effects
				(font
					(size 1.27 1.27)
				)
				(justify left bottom)
				(hide yes)
			)
		)
		(pin "1"
		)
		(pin "2"
		)
		(instances
			(project "cm4-baseboard"
				(path ""
					(reference "R501")
					(unit 1)
				)
			)
		)
	)
	(symbol
		(lib_id "antmicroTVSDiodes:TPD1E0B04_XDFN-2")
		(at 285.75 198.12 270)
		(mirror x)
		(unit 1)
		(exclude_from_sim no)
		(in_bom yes)
		(on_board yes)
		(dnp no)
		(fields_autoplaced yes)
		(property "Reference" "D504"
			(at 288.29 194.31 90)
			(effects
				(font
					(size 1.27 1.27)
				)
				(justify left)
			)
		)
		(property "Value" "TPD1E0B04_XDFN-2"
			(at 288.29 196.8499 90)
			(effects
				(font
					(size 1.27 1.27)
				)
				(justify left)
				(hide yes)
			)
		)
		(property "Footprint" "antmicro-footprints:XDFN-2_1x0.60mm"
			(at 290.83 193.04 0)
			(effects
				(font
					(size 1.524 1.524)
				)
				(justify left bottom)
				(hide yes)
			)
		)
		(property "Datasheet" "https://www.ti.com/general/docs/suppproductinfo.tsp?distId=26&gotoUrl=https://www.ti.com/lit/gpn/tpd1e0b04"
			(at 293.37 193.04 0)
			(effects
				(font
					(size 1.524 1.524)
				)
				(justify left bottom)
				(hide yes)
			)
		)
		(property "Description" ""
			(at 285.75 198.12 0)
			(effects
				(font
					(size 1.27 1.27)
				)
				(hide yes)
			)
		)
		(property "Manufacturer" "Texas Instruments"
			(at 313.69 193.04 0)
			(effects
				(font
					(size 1.524 1.524)
				)
				(justify left bottom)
				(hide yes)
			)
		)
		(property "MPN" "TPD1E0B04DPYR"
			(at 288.29 196.85 90)
			(effects
				(font
					(size 1.524 1.524)
				)
				(justify left)
			)
		)
		(property "Author" "Antmicro"
			(at 270.51 182.88 0)
			(effects
				(font
					(size 1.27 1.27)
					(thickness 0.15)
				)
				(justify left bottom)
				(hide yes)
			)
		)
		(property "License" "Apache-2.0"
			(at 267.97 182.88 0)
			(effects
				(font
					(size 1.27 1.27)
					(thickness 0.15)
				)
				(justify left bottom)
				(hide yes)
			)
		)
		(pin "1"
		)
		(pin "2"
		)
		(instances
			(project "cm4-baseboard"
				(path ""
					(reference "D504")
					(unit 1)
				)
			)
		)
	)
	(symbol
		(lib_id "antmicroCapacitors0402:C_1u_0402")
		(at 224.79 54.61 90)
		(unit 1)
		(exclude_from_sim no)
		(in_bom yes)
		(on_board yes)
		(dnp no)
		(property "Reference" "C502"
			(at 224.79 49.53 90)
			(effects
				(font
					(size 1.27 1.27)
				)
				(justify left)
			)
		)
		(property "Value" "C_1u_0402"
			(at 228.6 54.61 0)
			(effects
				(font
					(size 1.27 1.27)
				)
				(justify left bottom)
				(hide yes)
			)
		)
		(property "Footprint" "antmicro-footprints:C_0402_1005Metric"
			(at 219.71 49.53 0)
			(effects
				(font
					(size 1.524 1.524)
				)
				(justify left bottom)
				(hide yes)
			)
		)
		(property "Datasheet" "https://product.tdk.com/en/search/capacitor/ceramic/mlcc/info?part_no=C1005X6S1A105K050BC"
			(at 224.79 54.61 0)
			(effects
				(font
					(size 1.27 1.27)
				)
				(justify left bottom)
				(hide yes)
			)
		)
		(property "Description" ""
			(at 224.79 54.61 0)
			(effects
				(font
					(size 1.27 1.27)
				)
				(hide yes)
			)
		)
		(property "Manufacturer" "TDK"
			(at 214.63 49.53 0)
			(effects
				(font
					(size 1.524 1.524)
				)
				(justify left bottom)
				(hide yes)
			)
		)
		(property "MPN" "C1005X6S1A105K050BC"
			(at 217.17 49.53 0)
			(effects
				(font
					(size 1.524 1.524)
				)
				(justify left bottom)
				(hide yes)
			)
		)
		(property "Val" "1u"
			(at 223.52 54.61 90)
			(effects
				(font
					(size 1.27 1.27)
				)
				(justify left)
			)
		)
		(property "License" "Apache-2.0"
			(at 247.65 34.29 0)
			(effects
				(font
					(size 1.27 1.27)
					(thickness 0.15)
				)
				(justify left bottom)
				(hide yes)
			)
		)
		(property "Author" "Antmicro"
			(at 250.19 34.29 0)
			(effects
				(font
					(size 1.27 1.27)
					(thickness 0.15)
				)
				(justify left bottom)
				(hide yes)
			)
		)
		(property "Voltage" ""
			(at 252.73 34.29 0)
			(effects
				(font
					(size 1.27 1.27)
				)
				(justify left bottom)
				(hide yes)
			)
		)
		(property "Dielectric" ""
			(at 255.27 34.29 0)
			(effects
				(font
					(size 1.27 1.27)
				)
				(justify left bottom)
				(hide yes)
			)
		)
		(pin "1"
		)
		(pin "2"
		)
		(instances
			(project "cm4-baseboard"
				(path ""
					(reference "C502")
					(unit 1)
				)
			)
		)
	)
	(symbol
		(lib_id "antmicroCapacitors0402:C_10u_0402")
		(at 252.73 54.61 90)
		(unit 1)
		(exclude_from_sim no)
		(in_bom yes)
		(on_board yes)
		(dnp no)
		(property "Reference" "C505"
			(at 252.73 49.53 90)
			(effects
				(font
					(size 1.27 1.27)
					(thickness 0.15)
				)
				(justify left)
			)
		)
		(property "Value" "C_10u_0402"
			(at 262.89 34.29 0)
			(effects
				(font
					(size 1.27 1.27)
					(thickness 0.15)
				)
				(justify left bottom)
				(hide yes)
			)
		)
		(property "Footprint" "antmicro-footprints:C_0402_1005Metric"
			(at 265.43 34.29 0)
			(effects
				(font
					(size 1.27 1.27)
					(thickness 0.15)
				)
				(justify left bottom)
				(hide yes)
			)
		)
		(property "Datasheet" "https://www.yageo.com/en/Chart/Download/pdf/CC0402MRX5R5BB106"
			(at 267.97 34.29 0)
			(effects
				(font
					(size 1.27 1.27)
					(thickness 0.15)
				)
				(justify left bottom)
				(hide yes)
			)
		)
		(property "Description" ""
			(at 252.73 54.61 0)
			(effects
				(font
					(size 1.27 1.27)
				)
				(hide yes)
			)
		)
		(property "MPN" "CC0402MRX5R5BB106"
			(at 270.51 34.29 0)
			(effects
				(font
					(size 1.27 1.27)
					(thickness 0.15)
				)
				(justify left bottom)
				(hide yes)
			)
		)
		(property "Manufacturer" "YAGEO"
			(at 273.05 34.29 0)
			(effects
				(font
					(size 1.27 1.27)
					(thickness 0.15)
				)
				(justify left bottom)
				(hide yes)
			)
		)
		(property "License" "Apache-2.0"
			(at 275.59 34.29 0)
			(effects
				(font
					(size 1.27 1.27)
					(thickness 0.15)
				)
				(justify left bottom)
				(hide yes)
			)
		)
		(property "Author" "Antmicro"
			(at 278.13 34.29 0)
			(effects
				(font
					(size 1.27 1.27)
					(thickness 0.15)
				)
				(justify left bottom)
				(hide yes)
			)
		)
		(property "Val" "10u"
			(at 252.73 54.61 90)
			(effects
				(font
					(size 1.27 1.27)
					(thickness 0.15)
				)
				(justify left)
			)
		)
		(property "Voltage" ""
			(at 280.67 34.29 0)
			(effects
				(font
					(size 1.27 1.27)
				)
				(justify left bottom)
				(hide yes)
			)
		)
		(property "Dielectric" ""
			(at 283.21 34.29 0)
			(effects
				(font
					(size 1.27 1.27)
				)
				(justify left bottom)
				(hide yes)
			)
		)
		(pin "1"
		)
		(pin "2"
		)
		(instances
			(project "cm4-baseboard"
				(path ""
					(reference "C505")
					(unit 1)
				)
			)
		)
	)
	(symbol
		(lib_id "antmicroTVSDiodes:PUSB3F96X_PASS")
		(at 149.86 196.85 0)
		(mirror y)
		(unit 1)
		(exclude_from_sim no)
		(in_bom yes)
		(on_board yes)
		(dnp no)
		(fields_autoplaced yes)
		(property "Reference" "D501"
			(at 142.24 189.23 0)
			(effects
				(font
					(size 1.27 1.27)
					(thickness 0.15)
				)
			)
		)
		(property "Value" "PUSB3F96X_PASS"
			(at 124.46 204.47 0)
			(effects
				(font
					(size 1.27 1.27)
					(thickness 0.15)
				)
				(justify left bottom)
				(hide yes)
			)
		)
		(property "Footprint" "antmicro-footprints:Nexperia_DFN-10_2.5x1mm_P0.5mm"
			(at 124.46 207.01 0)
			(effects
				(font
					(size 1.27 1.27)
					(thickness 0.15)
				)
				(justify left bottom)
				(hide yes)
			)
		)
		(property "Datasheet" "https://mouser.com/datasheet/2/916/PUSB3F96-1600324.pdf"
			(at 124.46 209.55 0)
			(effects
				(font
					(size 1.27 1.27)
					(thickness 0.15)
				)
				(justify left bottom)
				(hide yes)
			)
		)
		(property "Description" ""
			(at 149.86 196.85 0)
			(effects
				(font
					(size 1.27 1.27)
				)
				(hide yes)
			)
		)
		(property "Manufacturer" "Nexperia"
			(at 124.46 212.09 0)
			(effects
				(font
					(size 1.27 1.27)
					(thickness 0.15)
				)
				(justify left bottom)
				(hide yes)
			)
		)
		(property "MPN" "PUSB3F96X"
			(at 142.24 191.77 0)
			(effects
				(font
					(size 1.27 1.27)
					(thickness 0.15)
				)
			)
		)
		(property "Author" "Antmicro"
			(at 124.46 214.63 0)
			(effects
				(font
					(size 1.27 1.27)
					(thickness 0.15)
				)
				(justify left bottom)
				(hide yes)
			)
		)
		(property "License" "Apache-2.0"
			(at 124.46 217.17 0)
			(effects
				(font
					(size 1.27 1.27)
					(thickness 0.15)
				)
				(justify left bottom)
				(hide yes)
			)
		)
		(pin "1"
		)
		(pin "10"
		)
		(pin "2"
		)
		(pin "3"
		)
		(pin "4"
		)
		(pin "5"
		)
		(pin "6"
		)
		(pin "7"
		)
		(pin "8"
		)
		(pin "9"
		)
		(instances
			(project "cm4-baseboard"
				(path ""
					(reference "D501")
					(unit 1)
				)
			)
		)
	)
	(symbol
		(lib_id "antmicroTVSDiodes:PUSB3F96X_PASS")
		(at 149.86 219.71 0)
		(mirror y)
		(unit 1)
		(exclude_from_sim no)
		(in_bom yes)
		(on_board yes)
		(dnp no)
		(fields_autoplaced yes)
		(property "Reference" "D502"
			(at 142.24 212.09 0)
			(effects
				(font
					(size 1.27 1.27)
					(thickness 0.15)
				)
			)
		)
		(property "Value" "PUSB3F96X_PASS"
			(at 124.46 227.33 0)
			(effects
				(font
					(size 1.27 1.27)
					(thickness 0.15)
				)
				(justify left bottom)
				(hide yes)
			)
		)
		(property "Footprint" "antmicro-footprints:Nexperia_DFN-10_2.5x1mm_P0.5mm"
			(at 124.46 229.87 0)
			(effects
				(font
					(size 1.27 1.27)
					(thickness 0.15)
				)
				(justify left bottom)
				(hide yes)
			)
		)
		(property "Datasheet" "https://mouser.com/datasheet/2/916/PUSB3F96-1600324.pdf"
			(at 124.46 232.41 0)
			(effects
				(font
					(size 1.27 1.27)
					(thickness 0.15)
				)
				(justify left bottom)
				(hide yes)
			)
		)
		(property "Description" ""
			(at 149.86 219.71 0)
			(effects
				(font
					(size 1.27 1.27)
				)
				(hide yes)
			)
		)
		(property "Manufacturer" "Nexperia"
			(at 124.46 234.95 0)
			(effects
				(font
					(size 1.27 1.27)
					(thickness 0.15)
				)
				(justify left bottom)
				(hide yes)
			)
		)
		(property "MPN" "PUSB3F96X"
			(at 142.24 214.63 0)
			(effects
				(font
					(size 1.27 1.27)
					(thickness 0.15)
				)
			)
		)
		(property "Author" "Antmicro"
			(at 124.46 237.49 0)
			(effects
				(font
					(size 1.27 1.27)
					(thickness 0.15)
				)
				(justify left bottom)
				(hide yes)
			)
		)
		(property "License" "Apache-2.0"
			(at 124.46 240.03 0)
			(effects
				(font
					(size 1.27 1.27)
					(thickness 0.15)
				)
				(justify left bottom)
				(hide yes)
			)
		)
		(pin "1"
		)
		(pin "10"
		)
		(pin "2"
		)
		(pin "3"
		)
		(pin "4"
		)
		(pin "5"
		)
		(pin "6"
		)
		(pin "7"
		)
		(pin "8"
		)
		(pin "9"
		)
		(instances
			(project "cm4-baseboard"
				(path ""
					(reference "D502")
					(unit 1)
				)
			)
		)
	)
	(symbol
		(lib_id "antmicroMemoryConnectorsPCCardSockets:MicroSD_1140084168")
		(at 243.84 199.39 0)
		(unit 1)
		(exclude_from_sim no)
		(in_bom yes)
		(on_board yes)
		(dnp no)
		(fields_autoplaced yes)
		(property "Reference" "J502"
			(at 257.175 191.77 0)
			(effects
				(font
					(size 1.27 1.27)
					(thickness 0.15)
				)
			)
		)
		(property "Value" "MicroSD_1140084168"
			(at 257.175 194.31 0)
			(effects
				(font
					(size 1.27 1.27)
					(thickness 0.15)
				)
				(hide yes)
			)
		)
		(property "Footprint" "antmicro-footprints:MicroSD_Amphenol_1140084168"
			(at 281.94 208.28 0)
			(effects
				(font
					(size 1.27 1.27)
					(thickness 0.15)
				)
				(justify left bottom)
				(hide yes)
			)
		)
		(property "Datasheet" "https://cdn.amphenol-cs.com/media/wysiwyg/files/documentation/datasheet/inputoutput/io_micro_sdcard.pdf"
			(at 281.94 210.82 0)
			(effects
				(font
					(size 1.27 1.27)
					(thickness 0.15)
				)
				(justify left bottom)
				(hide yes)
			)
		)
		(property "Description" ""
			(at 243.84 199.39 0)
			(effects
				(font
					(size 1.27 1.27)
				)
				(hide yes)
			)
		)
		(property "MPN" "1140084168"
			(at 257.175 194.31 0)
			(effects
				(font
					(size 1.27 1.27)
					(thickness 0.15)
				)
			)
		)
		(property "Manufacturer" "Amphenol"
			(at 281.94 215.9 0)
			(effects
				(font
					(size 1.27 1.27)
					(thickness 0.15)
				)
				(justify left bottom)
				(hide yes)
			)
		)
		(property "Author" "Antmicro"
			(at 281.94 218.44 0)
			(effects
				(font
					(size 1.27 1.27)
					(thickness 0.15)
				)
				(justify left bottom)
				(hide yes)
			)
		)
		(property "License" "Apache-2.0"
			(at 281.94 220.98 0)
			(effects
				(font
					(size 1.27 1.27)
					(thickness 0.15)
				)
				(justify left bottom)
				(hide yes)
			)
		)
		(pin "1"
		)
		(pin "10"
		)
		(pin "2"
		)
		(pin "3"
		)
		(pin "4"
		)
		(pin "5"
		)
		(pin "6"
		)
		(pin "7"
		)
		(pin "8"
		)
		(pin "9"
		)
		(pin "SH"
		)
		(instances
			(project "cm4-baseboard"
				(path ""
					(reference "J502")
					(unit 1)
				)
			)
		)
	)
	(symbol
		(lib_id "antmicroPciConnectors:Bus_M.2_1-2199230-6")
		(at 172.72 46.99 0)
		(unit 1)
		(exclude_from_sim no)
		(in_bom yes)
		(on_board yes)
		(dnp no)
		(fields_autoplaced yes)
		(property "Reference" "J501"
			(at 187.96 39.37 0)
			(effects
				(font
					(size 1.27 1.27)
					(thickness 0.15)
				)
			)
		)
		(property "Value" "Bus_M.2_1-2199230-6"
			(at 218.44 54.61 0)
			(effects
				(font
					(size 1.27 1.27)
					(thickness 0.15)
				)
				(justify left bottom)
				(hide yes)
			)
		)
		(property "Footprint" "antmicro-footprints:Bus_M.2_Socket_Key_M_TE_1-2199230-6"
			(at 218.44 57.15 0)
			(effects
				(font
					(size 1.27 1.27)
					(thickness 0.15)
				)
				(justify left bottom)
				(hide yes)
			)
		)
		(property "Datasheet" "https://www.te.com/commerce/DocumentDelivery/DDEController?Action=srchrtrv&DocNm=2199230&DocType=Customer+Drawing&DocLang=English"
			(at 218.44 59.69 0)
			(effects
				(font
					(size 1.27 1.27)
					(thickness 0.15)
				)
				(justify left bottom)
				(hide yes)
			)
		)
		(property "Description" ""
			(at 172.72 46.99 0)
			(effects
				(font
					(size 1.27 1.27)
				)
				(hide yes)
			)
		)
		(property "Manufacturer" "TE Connectivity"
			(at 218.44 62.23 0)
			(effects
				(font
					(size 1.27 1.27)
					(thickness 0.15)
				)
				(justify left bottom)
				(hide yes)
			)
		)
		(property "MPN" "1-2199230-6"
			(at 187.96 41.91 0)
			(effects
				(font
					(size 1.27 1.27)
					(thickness 0.15)
				)
			)
		)
		(property "Author" "Antmicro"
			(at 218.44 64.77 0)
			(effects
				(font
					(size 1.27 1.27)
					(thickness 0.15)
				)
				(justify left bottom)
				(hide yes)
			)
		)
		(property "License" "Apache-2.0"
			(at 218.44 67.31 0)
			(effects
				(font
					(size 1.27 1.27)
					(thickness 0.15)
				)
				(justify left bottom)
				(hide yes)
			)
		)
		(pin "1"
		)
		(pin "10"
		)
		(pin "11"
		)
		(pin "12"
		)
		(pin "13"
		)
		(pin "14"
		)
		(pin "15"
		)
		(pin "16"
		)
		(pin "17"
		)
		(pin "18"
		)
		(pin "19"
		)
		(pin "2"
		)
		(pin "20"
		)
		(pin "21"
		)
		(pin "22"
		)
		(pin "23"
		)
		(pin "24"
		)
		(pin "25"
		)
		(pin "26"
		)
		(pin "27"
		)
		(pin "28"
		)
		(pin "29"
		)
		(pin "3"
		)
		(pin "30"
		)
		(pin "31"
		)
		(pin "32"
		)
		(pin "33"
		)
		(pin "34"
		)
		(pin "35"
		)
		(pin "36"
		)
		(pin "37"
		)
		(pin "38"
		)
		(pin "39"
		)
		(pin "4"
		)
		(pin "40"
		)
		(pin "41"
		)
		(pin "42"
		)
		(pin "43"
		)
		(pin "44"
		)
		(pin "45"
		)
		(pin "46"
		)
		(pin "47"
		)
		(pin "48"
		)
		(pin "49"
		)
		(pin "5"
		)
		(pin "50"
		)
		(pin "51"
		)
		(pin "52"
		)
		(pin "53"
		)
		(pin "54"
		)
		(pin "55"
		)
		(pin "56"
		)
		(pin "57"
		)
		(pin "58"
		)
		(pin "6"
		)
		(pin "67"
		)
		(pin "68"
		)
		(pin "69"
		)
		(pin "7"
		)
		(pin "70"
		)
		(pin "71"
		)
		(pin "72"
		)
		(pin "73"
		)
		(pin "74"
		)
		(pin "75"
		)
		(pin "8"
		)
		(pin "9"
		)
		(pin "MP1"
		)
		(pin "MP2"
		)
		(instances
			(project "cm4-baseboard"
				(path ""
					(reference "J501")
					(unit 1)
				)
			)
		)
	)
	(symbol
		(lib_id "antmicropower:GND")
		(at 266.7 121.92 0)
		(mirror y)
		(unit 1)
		(exclude_from_sim no)
		(in_bom yes)
		(on_board yes)
		(dnp no)
		(fields_autoplaced yes)
		(property "Reference" "#PWR0513"
			(at 257.81 124.46 0)
			(effects
				(font
					(size 1.27 1.27)
					(thickness 0.15)
				)
				(justify left bottom)
				(hide yes)
			)
		)
		(property "Value" "GND"
			(at 268.7102 127 0)
			(effects
				(font
					(size 1.27 1.27)
					(thickness 0.15)
				)
				(justify left bottom)
			)
		)
		(property "Footprint" ""
			(at 257.81 129.54 0)
			(effects
				(font
					(size 1.27 1.27)
					(thickness 0.15)
				)
				(justify left bottom)
				(hide yes)
			)
		)
		(property "Datasheet" ""
			(at 257.81 134.62 0)
			(effects
				(font
					(size 1.27 1.27)
					(thickness 0.15)
				)
				(justify left bottom)
				(hide yes)
			)
		)
		(property "Description" ""
			(at 266.7 121.92 0)
			(effects
				(font
					(size 1.27 1.27)
				)
				(hide yes)
			)
		)
		(property "Author" "Antmicro"
			(at 257.81 129.54 0)
			(effects
				(font
					(size 1.27 1.27)
					(thickness 0.15)
				)
				(justify left bottom)
				(hide yes)
			)
		)
		(property "License" "Apache-2.0"
			(at 257.81 132.08 0)
			(effects
				(font
					(size 1.27 1.27)
					(thickness 0.15)
				)
				(justify left bottom)
				(hide yes)
			)
		)
		(pin "1"
		)
		(instances
			(project "cm4-baseboard"
				(path ""
					(reference "#PWR0513")
					(unit 1)
				)
			)
		)
	)
	(symbol
		(lib_id "antmicropower:GND")
		(at 151.13 231.14 0)
		(mirror y)
		(unit 1)
		(exclude_from_sim no)
		(in_bom yes)
		(on_board yes)
		(dnp no)
		(fields_autoplaced yes)
		(property "Reference" "#PWR0503"
			(at 142.24 233.68 0)
			(effects
				(font
					(size 1.27 1.27)
					(thickness 0.15)
				)
				(justify left bottom)
				(hide yes)
			)
		)
		(property "Value" "GND"
			(at 153.1402 236.22 0)
			(effects
				(font
					(size 1.27 1.27)
					(thickness 0.15)
				)
				(justify left bottom)
			)
		)
		(property "Footprint" ""
			(at 142.24 238.76 0)
			(effects
				(font
					(size 1.27 1.27)
					(thickness 0.15)
				)
				(justify left bottom)
				(hide yes)
			)
		)
		(property "Datasheet" ""
			(at 142.24 243.84 0)
			(effects
				(font
					(size 1.27 1.27)
					(thickness 0.15)
				)
				(justify left bottom)
				(hide yes)
			)
		)
		(property "Description" ""
			(at 151.13 231.14 0)
			(effects
				(font
					(size 1.27 1.27)
				)
				(hide yes)
			)
		)
		(property "Author" "Antmicro"
			(at 142.24 238.76 0)
			(effects
				(font
					(size 1.27 1.27)
					(thickness 0.15)
				)
				(justify left bottom)
				(hide yes)
			)
		)
		(property "License" "Apache-2.0"
			(at 142.24 241.3 0)
			(effects
				(font
					(size 1.27 1.27)
					(thickness 0.15)
				)
				(justify left bottom)
				(hide yes)
			)
		)
		(pin "1"
		)
		(instances
			(project "cm4-baseboard"
				(path ""
					(reference "#PWR0503")
					(unit 1)
				)
			)
		)
	)
	(symbol
		(lib_id "antmicropower:+3V3")
		(at 275.59 191.77 0)
		(unit 1)
		(exclude_from_sim no)
		(in_bom yes)
		(on_board yes)
		(dnp no)
		(fields_autoplaced yes)
		(property "Reference" "#PWR0514"
			(at 290.83 194.31 0)
			(effects
				(font
					(size 1.27 1.27)
					(thickness 0.15)
				)
				(justify left bottom)
				(hide yes)
			)
		)
		(property "Value" "+3V3"
			(at 275.59 186.69 0)
			(effects
				(font
					(size 1.27 1.27)
					(thickness 0.15)
				)
			)
		)
		(property "Footprint" ""
			(at 290.83 199.39 0)
			(effects
				(font
					(size 1.27 1.27)
					(thickness 0.15)
				)
				(justify left bottom)
				(hide yes)
			)
		)
		(property "Datasheet" ""
			(at 290.83 201.93 0)
			(effects
				(font
					(size 1.27 1.27)
					(thickness 0.15)
				)
				(justify left bottom)
				(hide yes)
			)
		)
		(property "Description" ""
			(at 275.59 191.77 0)
			(effects
				(font
					(size 1.27 1.27)
				)
				(hide yes)
			)
		)
		(property "Author" "Antmicro"
			(at 290.83 199.39 0)
			(effects
				(font
					(size 1.27 1.27)
					(thickness 0.15)
				)
				(justify left bottom)
				(hide yes)
			)
		)
		(property "License" "Apache-2.0"
			(at 290.83 201.93 0)
			(effects
				(font
					(size 1.27 1.27)
					(thickness 0.15)
				)
				(justify left bottom)
				(hide yes)
			)
		)
		(pin "1"
		)
		(instances
			(project "cm4-baseboard"
				(path ""
					(reference "#PWR0514")
					(unit 1)
				)
			)
		)
	)
)
